(kicad_pcb
	(version 20260206)
	(generator "pcbnew")
	(generator_version "10.0")
	(general
		(thickness 1.5755)
		(legacy_teardrops no)
	)
	(paper "A4")
	(layers
		(0 "F.Cu" signal "Top Layer")
		(4 "In1.Cu" signal "Int1 (GND)")
		(6 "In2.Cu" signal "Int2 (GND)")
		(2 "B.Cu" signal "Bottom Layer")
		(9 "F.Adhes" user "F.Adhesive")
		(11 "B.Adhes" user "B.Adhesive")
		(13 "F.Paste" user "Top Paste")
		(15 "B.Paste" user "Bottom Paste")
		(5 "F.SilkS" user "Top Overlay")
		(7 "B.SilkS" user "Bottom Overlay")
		(1 "F.Mask" user "Top Solder")
		(3 "B.Mask" user "Bottom Solder")
		(17 "Dwgs.User" user "User.Drawings")
		(19 "Cmts.User" user "User.Comments")
		(21 "Eco1.User" user "User.Eco1")
		(23 "Eco2.User" user "User.Eco2")
		(25 "Edge.Cuts" user)
		(27 "Margin" user)
		(31 "F.CrtYd" user "Top Courtyard")
		(29 "B.CrtYd" user "Bottom Courtyard")
		(35 "F.Fab" user "Top Component Outline")
		(33 "B.Fab" user "Bottom Component Outline")
	)
	(setup
		(pad_to_mask_clearance 0.0508)
		(allow_soldermask_bridges_in_footprints no)
		(tenting
			(front yes)
			(back yes)
		)
		(covering
			(front no)
			(back no)
		)
		(plugging
			(front no)
			(back no)
		)
		(capping no)
		(filling no)
		(aux_axis_origin 114.77975 120.75945)
		(grid_origin 114.77975 120.75945)
		(pcbplotparams
			(layerselection 0x00000000_00000000_55555555_5755f5ff)
			(plot_on_all_layers_selection 0x00000000_00000000_00000000_00000000)
			(disableapertmacros no)
			(usegerberextensions no)
			(usegerberattributes yes)
			(usegerberadvancedattributes yes)
			(creategerberjobfile yes)
			(dashed_line_dash_ratio 12)
			(dashed_line_gap_ratio 3)
			(svgprecision 4)
			(plotframeref no)
			(mode 1)
			(useauxorigin no)
			(pdf_front_fp_property_popups yes)
			(pdf_back_fp_property_popups yes)
			(pdf_metadata yes)
			(pdf_single_document no)
			(dxfpolygonmode yes)
			(dxfimperialunits yes)
			(dxfusepcbnewfont yes)
			(psnegative no)
			(psa4output no)
			(plot_black_and_white yes)
			(sketchpadsonfab no)
			(plotpadnumbers no)
			(hidednponfab no)
			(sketchdnponfab yes)
			(crossoutdnponfab yes)
			(subtractmaskfromsilk no)
			(outputformat 1)
			(mirror no)
			(drillshape 1)
			(scaleselection 1)
			(outputdirectory "")
		)
	)
	(footprint "Vault:LEDS160X80X110-2N_LXFM0603-GR"
		(layer "F.Cu")
		(at 169.7537 116.6597 90)
		(property "Reference" "DS3"
			(at 2.77425 0.62377 0)
			(unlocked yes)
			(layer "F.SilkS")
			(effects
				(font
					(size 0.8 0.8)
					(thickness 0.15)
				)
			)
		)
		(property "Value" "Lumex_SML-LXFM0603SUGCTR"
			(at -3.318002 17.78687 0)
			(unlocked yes)
			(layer "F.SilkS")
			(hide yes)
			(effects
				(font
					(size 1.524 1.524)
					(thickness 0.254)
				)
			)
		)
		(sheetname "ZED-F9T")
		(sheetfile "ZED-F9T.kicad_sch")
		(duplicate_pad_numbers_are_jumpers no)
		(fp_line
			(start -1.6 -0.3)
			(end -1.6 0.3)
			(stroke
				(width 0.1)
				(type solid)
			)
			(layer "F.SilkS")
		)
		(fp_line
			(start 1.7 -0.7)
			(end 1.7 0.7)
			(stroke
				(width 0.1)
				(type solid)
			)
			(layer "F.CrtYd")
		)
		(fp_line
			(start -1.7 -0.7)
			(end 1.7 -0.7)
			(stroke
				(width 0.1)
				(type solid)
			)
			(layer "F.CrtYd")
		)
		(fp_line
			(start -1.7 -0.7)
			(end -1.7 0.7)
			(stroke
				(width 0.1)
				(type solid)
			)
			(layer "F.CrtYd")
		)
		(fp_line
			(start -1.7 0.7)
			(end 1.7 0.7)
			(stroke
				(width 0.1)
				(type solid)
			)
			(layer "F.CrtYd")
		)
		(fp_line
			(start 0.80017 -0.40012)
			(end 0.80017 0.39984)
			(stroke
				(width 0.05)
				(type solid)
			)
			(layer "F.Fab")
		)
		(fp_line
			(start -0.79991 -0.40012)
			(end 0.80017 -0.40012)
			(stroke
				(width 0.05)
				(type solid)
			)
			(layer "F.Fab")
		)
		(fp_line
			(start -0.79991 -0.40012)
			(end -0.79991 0.39984)
			(stroke
				(width 0.05)
				(type solid)
			)
			(layer "F.Fab")
		)
		(fp_line
			(start -0.1 -0.3)
			(end -0.1 0.3)
			(stroke
				(width 0.05)
				(type solid)
			)
			(layer "F.Fab")
		)
		(fp_line
			(start 0.1 -0.2)
			(end -0.1 0)
			(stroke
				(width 0.05)
				(type solid)
			)
			(layer "F.Fab")
		)
		(fp_line
			(start 0.1 -0.2)
			(end 0.1 0.2)
			(stroke
				(width 0.05)
				(type solid)
			)
			(layer "F.Fab")
		)
		(fp_line
			(start -0.1 0)
			(end 0.1 0.2)
			(stroke
				(width 0.05)
				(type solid)
			)
			(layer "F.Fab")
		)
		(fp_line
			(start -0.79991 0.39984)
			(end 0.80017 0.39984)
			(stroke
				(width 0.05)
				(type solid)
			)
			(layer "F.Fab")
		)
		(fp_text_box "${REFERENCE}"
			(start -2.76576 -0.52568)
			(end 2.76577 0.52568)
			(margins 0 0 0 0)
			(layer "F.Fab")
			(effects
				(font
					(face "Arial")
					(size 0.8001 0.8001)
					(thickness 0.254)
				)
				(justify top)
			)
			(border no)
			(stroke
				(width 0.1)
				(type default)
			)
			(knockout no)
		)
		(pad "A" smd rect
			(at 0.825 0 90)
			(size 0.8 0.8)
			(layers "F.Cu" "F.Mask" "F.Paste")
			(net "VCC_ANT")
			(solder_mask_margin 0.05)
			(solder_paste_margin 0)
		)
		(pad "K" smd rect
			(at -0.825 0 90)
			(size 0.8 0.8)
			(layers "F.Cu" "F.Mask" "F.Paste")
			(net "NetDS3_K")
			(solder_mask_margin 0.05)
			(solder_paste_margin 0)
		)
	)
	(footprint "Vault:FP-RMCF0402-MFG"
		(layer "F.Cu")
		(at 168.8647 103.9597 90)
		(property "Reference" "R3"
			(at 2.35981 0.20607 90)
			(unlocked yes)
			(layer "F.SilkS")
			(effects
				(font
					(size 0.8 0.8)
					(thickness 0.15001)
				)
			)
		)
		(property "Value" "1k"
			(at 0.57117 2.378202 90)
			(unlocked yes)
			(layer "F.SilkS")
			(hide yes)
			(effects
				(font
					(size 1.524 1.524)
					(thickness 0.254)
				)
			)
		)
		(sheetname "ZED-F9T")
		(sheetfile "ZED-F9T.kicad_sch")
		(duplicate_pad_numbers_are_jumpers no)
		(fp_line
			(start -0.55 -0.7)
			(end 0.55 -0.7)
			(stroke
				(width 0.2)
				(type solid)
			)
			(layer "F.SilkS")
		)
		(fp_line
			(start -0.55 0.7)
			(end 0.55 0.7)
			(stroke
				(width 0.2)
				(type solid)
			)
			(layer "F.SilkS")
		)
		(fp_line
			(start 0.85 -0.4)
			(end 0.85 0.4)
			(stroke
				(width 0.2)
				(type solid)
			)
			(layer "F.CrtYd")
		)
		(fp_line
			(start -0.85 -0.4)
			(end 0.85 -0.4)
			(stroke
				(width 0.2)
				(type solid)
			)
			(layer "F.CrtYd")
		)
		(fp_line
			(start -0.85 -0.4)
			(end -0.85 0.4)
			(stroke
				(width 0.2)
				(type solid)
			)
			(layer "F.CrtYd")
		)
		(fp_line
			(start -0.85 0.4)
			(end 0.85 0.4)
			(stroke
				(width 0.2)
				(type solid)
			)
			(layer "F.CrtYd")
		)
		(fp_line
			(start 0 -0.5)
			(end 0 0.5)
			(stroke
				(width 0.1)
				(type solid)
			)
			(layer "F.Fab")
		)
		(fp_line
			(start 0.85 -0.4)
			(end 0.85 0.4)
			(stroke
				(width 0.2)
				(type solid)
			)
			(layer "F.Fab")
		)
		(fp_line
			(start -0.85 -0.4)
			(end 0.85 -0.4)
			(stroke
				(width 0.2)
				(type solid)
			)
			(layer "F.Fab")
		)
		(fp_line
			(start -0.85 -0.4)
			(end -0.85 0.4)
			(stroke
				(width 0.2)
				(type solid)
			)
			(layer "F.Fab")
		)
		(fp_line
			(start -0.5 0)
			(end 0.5 0)
			(stroke
				(width 0.1)
				(type solid)
			)
			(layer "F.Fab")
		)
		(fp_line
			(start -0.85 0.4)
			(end 0.85 0.4)
			(stroke
				(width 0.2)
				(type solid)
			)
			(layer "F.Fab")
		)
		(fp_text user "${REFERENCE}"
			(at -0.00001 0.09556 90)
			(unlocked yes)
			(layer "F.Fab")
			(effects
				(font
					(face "Arial")
					(size 0.63 0.63)
					(thickness 0.1)
				)
				(justify left bottom)
			)
		)
		(pad "1" smd rect
			(at -0.5 0 90)
			(size 0.5 0.6)
			(layers "F.Cu" "F.Mask" "F.Paste")
			(net "TXD_OUT")
			(solder_mask_margin 0)
			(solder_paste_margin 0)
		)
		(pad "2" smd rect
			(at 0.5 0 90)
			(size 0.5 0.6)
			(layers "F.Cu" "F.Mask" "F.Paste")
			(net "VCC")
			(solder_mask_margin 0)
			(solder_paste_margin 0)
		)
	)
	(footprint "Vault:CAPC1005X055N"
		(layer "F.Cu")
		(at 156.4441 107.7951)
		(property "Reference" "C2"
			(at 2.055 0.02827 0)
			(unlocked yes)
			(layer "F.SilkS")
			(effects
				(font
					(size 0.8 0.8)
					(thickness 0.15)
				)
			)
		)
		(property "Value" "Murata_GRM155R61E105KA12D"
			(at 17.659825 2.124202 0)
			(unlocked yes)
			(layer "F.SilkS")
			(hide yes)
			(effects
				(font
					(size 1.524 1.524)
					(thickness 0.254)
				)
			)
		)
		(sheetname "ZED-F9T")
		(sheetfile "ZED-F9T.kicad_sch")
		(duplicate_pad_numbers_are_jumpers no)
		(fp_line
			(start -0.95 -0.5)
			(end 0.95 -0.5)
			(stroke
				(width 0.1)
				(type solid)
			)
			(layer "F.CrtYd")
		)
		(fp_line
			(start -0.95 0.5)
			(end -0.95 -0.5)
			(stroke
				(width 0.1)
				(type solid)
			)
			(layer "F.CrtYd")
		)
		(fp_line
			(start -0.95 0.5)
			(end 0.95 0.5)
			(stroke
				(width 0.1)
				(type solid)
			)
			(layer "F.CrtYd")
		)
		(fp_line
			(start 0.95 0.5)
			(end 0.95 -0.5)
			(stroke
				(width 0.1)
				(type solid)
			)
			(layer "F.CrtYd")
		)
		(fp_line
			(start -0.5 -0.25)
			(end 0.5 -0.25)
			(stroke
				(width 0.05)
				(type solid)
			)
			(layer "F.Fab")
		)
		(fp_line
			(start -0.5 0.25)
			(end -0.5 -0.25)
			(stroke
				(width 0.05)
				(type solid)
			)
			(layer "F.Fab")
		)
		(fp_line
			(start -0.5 0.25)
			(end 0.5 0.25)
			(stroke
				(width 0.05)
				(type solid)
			)
			(layer "F.Fab")
		)
		(fp_line
			(start 0.5 0.25)
			(end 0.5 -0.25)
			(stroke
				(width 0.05)
				(type solid)
			)
			(layer "F.Fab")
		)
		(fp_text_box "${REFERENCE}"
			(start -1.09004 -0.20727)
			(end 1.09004 0.20726)
			(margins 0 0 0 0)
			(layer "F.Fab")
			(effects
				(font
					(face "Arial")
					(size 0.315 0.315)
					(thickness 0.254)
				)
				(justify top)
			)
			(border no)
			(stroke
				(width 0.1)
				(type default)
			)
			(knockout no)
		)
		(pad "1" smd rect
			(at -0.46 0)
			(size 0.6 0.62)
			(layers "F.Cu" "F.Mask" "F.Paste")
			(net "VCC")
			(solder_mask_margin 0.05)
			(solder_paste_margin 0)
		)
		(pad "2" smd rect
			(at 0.46 0)
			(size 0.6 0.62)
			(layers "F.Cu" "F.Mask" "F.Paste")
			(net "GND")
			(solder_mask_margin 0.05)
			(solder_paste_margin 0)
		)
	)
	(footprint "GNSS_Receiver_Library:NRPN042MAMS-RC"
		(locked yes)
		(layer "F.Cu")
		(at 178.2601 112.5961 180)
		(property "Reference" "J1"
			(at 5.24079 8.08325 0)
			(unlocked yes)
			(layer "F.SilkS")
			(effects
				(font
					(size 0.8 0.8)
					(thickness 0.15)
				)
			)
		)
		(property "Value" "NRPN042MAMS-RC"
			(at -0.231135 -4.626602 0)
			(unlocked yes)
			(layer "F.SilkS")
			(hide yes)
			(effects
				(font
					(size 1.524 1.524)
					(thickness 0.254)
				)
			)
		)
		(sheetname "ZED-F9T")
		(sheetfile "ZED-F9T.kicad_sch")
		(duplicate_pad_numbers_are_jumpers no)
		(fp_circle
			(center -2.2 0)
			(end -2.2 0.0762)
			(stroke
				(width 0.508)
				(type solid)
			)
			(fill no)
			(layer "F.SilkS")
		)
		(pad "1" smd rect
			(at 0 0 180)
			(size 2.95 1.02)
			(layers "F.Cu" "F.Mask" "F.Paste")
			(net "VCC_ANT")
		)
		(pad "2" smd rect
			(at 4.55 0 180)
			(size 2.95 1.02)
			(layers "F.Cu" "F.Mask" "F.Paste")
			(net "VCC")
		)
		(pad "3" smd rect
			(at 0 2 180)
			(size 2.95 1.02)
			(layers "F.Cu" "F.Mask" "F.Paste")
			(net "TXD_OUT")
		)
		(pad "4" smd rect
			(at 4.55 2 180)
			(size 2.95 1.02)
			(layers "F.Cu" "F.Mask" "F.Paste")
			(net "RST")
		)
		(pad "5" smd rect
			(at 0 4 180)
			(size 2.95 1.02)
			(layers "F.Cu" "F.Mask" "F.Paste")
			(net "RXD_IN")
		)
		(pad "6" smd rect
			(at 4.55 4 180)
			(size 2.95 1.02)
			(layers "F.Cu" "F.Mask" "F.Paste")
			(net "TP1")
		)
		(pad "7" smd rect
			(at 0 6 180)
			(size 2.95 1.02)
			(layers "F.Cu" "F.Mask" "F.Paste")
			(net "TP2")
		)
		(pad "8" smd rect
			(at 4.55 6 180)
			(size 2.95 1.02)
			(layers "F.Cu" "F.Mask" "F.Paste")
			(net "GND")
		)
	)
	(footprint "MyLibrary:CONN_131-3711-301"
		(locked yes)
		(layer "F.Cu")
		(at 120.7051 101.0761 -90)
		(property "Reference" "J2"
			(at -4.68273 -2.996 0)
			(unlocked yes)
			(layer "F.SilkS")
			(effects
				(font
					(size 0.8 0.8)
					(thickness 0.15)
				)
			)
		)
		(property "Value" "SMB_131-3711-301"
			(at 12.512802 -7.959285 0)
			(unlocked yes)
			(layer "F.SilkS")
			(hide yes)
			(effects
				(font
					(size 1.524 1.524)
					(thickness 0.254)
				)
			)
		)
		(sheetname "Antenna_Supervisor")
		(sheetfile "Antenna_Supervisor.kicad_sch")
		(duplicate_pad_numbers_are_jumpers no)
		(fp_line
			(start -3.8 3.8)
			(end -3.8 -3.8)
			(stroke
				(width 0.1778)
				(type solid)
			)
			(layer "F.SilkS")
		)
		(fp_line
			(start 3.8 3.8)
			(end -3.8 3.8)
			(stroke
				(width 0.1778)
				(type solid)
			)
			(layer "F.SilkS")
		)
		(fp_line
			(start 3.8 3.8)
			(end 3.8 -3.8)
			(stroke
				(width 0.1778)
				(type solid)
			)
			(layer "F.SilkS")
		)
		(fp_line
			(start 3.8 -3.8)
			(end -3.8 -3.8)
			(stroke
				(width 0.1778)
				(type solid)
			)
			(layer "F.SilkS")
		)
		(pad "" smd custom
			(at -3.58131 3.55582)
			(size 0.000001 0.000001)
			(layers "F.Cu" "F.Mask" "F.Paste")
			(solder_paste_margin -0.2)
			(thermal_bridge_angle 90)
			(options
				(clearance outline)
				(anchor circle)
			)
			(primitives
				(gr_poly
					(pts
						(xy 0 0) (xy 0 2.3622)
						(arc
							(start 1.914553 2.3622)
							(mid 3.556 1.5367)
							(end 5.197447 2.3622)
						)
						(xy 5.19744 2.3622) (xy 7.112 2.3622) (xy 7.112 0)
					)
					(width 0)
					(fill yes)
				)
			)
		)
		(pad "" smd custom
			(at -0.86351 -0.00018)
			(size 0.000001 0.000001)
			(layers "F.Cu" "F.Mask" "F.Paste")
			(solder_paste_margin -0.2)
			(thermal_bridge_angle 90)
			(options
				(clearance outline)
				(anchor circle)
			)
			(primitives
				(gr_poly
					(pts
						(arc
							(start 0 0)
							(mid -0.610657 0.252943)
							(end -0.8636 0.8636)
						)
						(arc
							(start -0.8636 0.8636)
							(mid -0.610657 1.474257)
							(end 0 1.7272)
						)
						(arc
							(start 0 1.7272)
							(mid 0.610657 1.474257)
							(end 0.8636 0.8636)
						)
						(arc
							(start 0.8636 0.8636)
							(mid 0.610657 0.252943)
							(end 0 0)
						)
					)
					(width 0)
					(fill yes)
				)
			)
		)
		(pad "" smd custom
			(at 1.21929 3.55582)
			(size 0.000001 0.000001)
			(layers "F.Cu" "F.Mask" "F.Paste")
			(solder_paste_margin -0.2)
			(thermal_bridge_angle 90)
			(options
				(clearance outline)
				(anchor circle)
			)
			(primitives
				(gr_poly
					(pts
						(xy 0 0) (xy 0 2.3622) (xy 7.112 2.3622) (xy 7.112 0)
						(arc
							(start 5.197447 0)
							(mid 3.556 0.8255)
							(end 1.914553 0)
						)
						(xy 1.91455 0)
					)
					(width 0)
					(fill yes)
				)
			)
		)
		(pad "1" smd circle
			(at 0.00009 -0.00018 270)
			(size 1 1)
			(layers "F.Cu" "F.Mask" "F.Paste")
			(net "RF_ANT")
			(solder_mask_margin 0)
			(thermal_bridge_angle 90)
		)
		(pad "2" smd rect
			(at -2.794 0.254 270)
			(size 1 5)
			(layers "F.Cu" "F.Mask" "F.Paste")
			(net "GND")
			(solder_mask_margin 0)
		)
		(pad "3" smd rect
			(at 2.91616 0 270)
			(size 1 5)
			(layers "F.Cu" "F.Mask" "F.Paste")
			(net "GND")
			(solder_mask_margin 0)
		)
	)
	(footprint "Vault:FP-RMCF0402-IPC_C"
		(layer "F.Cu")
		(at 163.7847 117.55363 -90)
		(property "Reference" "R7"
			(at 1.52194 -0.15 0)
			(unlocked yes)
			(layer "F.SilkS")
			(effects
				(font
					(size 0.8 0.8)
					(thickness 0.15)
				)
			)
		)
		(property "Value" "10k"
			(at 2.352802 -1.434525 0)
			(unlocked yes)
			(layer "F.SilkS")
			(hide yes)
			(effects
				(font
					(size 1.524 1.524)
					(thickness 0.254)
				)
			)
		)
		(sheetname "ZED-F9T")
		(sheetfile "ZED-F9T.kicad_sch")
		(duplicate_pad_numbers_are_jumpers no)
		(fp_line
			(start 0.65607 0.675)
			(end -0.65607 0.675)
			(stroke
				(width 0.2)
				(type solid)
			)
			(layer "F.SilkS")
		)
		(fp_line
			(start 0.65607 -0.675)
			(end -0.65607 -0.675)
			(stroke
				(width 0.2)
				(type solid)
			)
			(layer "F.SilkS")
		)
		(fp_line
			(start -0.75606 0.375)
			(end -0.75606 -0.375)
			(stroke
				(width 0.2)
				(type solid)
			)
			(layer "F.CrtYd")
		)
		(fp_line
			(start 0.75607 0.375)
			(end -0.75606 0.375)
			(stroke
				(width 0.2)
				(type solid)
			)
			(layer "F.CrtYd")
		)
		(fp_line
			(start 0.75607 0.375)
			(end 0.75607 -0.375)
			(stroke
				(width 0.2)
				(type solid)
			)
			(layer "F.CrtYd")
		)
		(fp_line
			(start 0.75607 -0.375)
			(end -0.75606 -0.375)
			(stroke
				(width 0.2)
				(type solid)
			)
			(layer "F.CrtYd")
		)
		(fp_line
			(start 0 0.5)
			(end 0 -0.5)
			(stroke
				(width 0.1)
				(type solid)
			)
			(layer "F.Fab")
		)
		(fp_line
			(start -0.75606 0.375)
			(end -0.75606 -0.375)
			(stroke
				(width 0.2)
				(type solid)
			)
			(layer "F.Fab")
		)
		(fp_line
			(start 0.75607 0.375)
			(end -0.75606 0.375)
			(stroke
				(width 0.2)
				(type solid)
			)
			(layer "F.Fab")
		)
		(fp_line
			(start 0.75607 0.375)
			(end 0.75607 -0.375)
			(stroke
				(width 0.2)
				(type solid)
			)
			(layer "F.Fab")
		)
		(fp_line
			(start 0.5 0)
			(end -0.5 0)
			(stroke
				(width 0.1)
				(type solid)
			)
			(layer "F.Fab")
		)
		(fp_line
			(start 0.75607 -0.375)
			(end -0.75606 -0.375)
			(stroke
				(width 0.2)
				(type solid)
			)
			(layer "F.Fab")
		)
		(fp_text user "${REFERENCE}"
			(at -0.00001 0.10711 270)
			(unlocked yes)
			(layer "F.Fab")
			(effects
				(font
					(face "Arial")
					(size 0.63 0.63)
					(thickness 0.1)
				)
				(justify left bottom)
			)
		)
		(pad "1" smd rect
			(at -0.36553 0 270)
			(size 0.58106 0.47247)
			(layers "F.Cu" "F.Mask" "F.Paste")
			(net "GND")
			(solder_mask_margin 0)
			(solder_paste_margin 0)
		)
		(pad "2" smd rect
			(at 0.36554 0 270)
			(size 0.58106 0.47247)
			(layers "F.Cu" "F.Mask" "F.Paste")
			(net "NetDS2_K")
			(solder_mask_margin 0)
			(solder_paste_margin 0)
		)
	)
	(footprint "Vault:CAPC1005X055N"
		(layer "F.Cu")
		(at 156.4441 109.1921)
		(property "Reference" "C1"
			(at 1.92171 0.02827 0)
			(unlocked yes)
			(layer "F.SilkS")
			(effects
				(font
					(size 0.8 0.8)
					(thickness 0.15)
				)
			)
		)
		(property "Value" "Murata_GRM155R61E105KA12D"
			(at 17.643125 9.764902 0)
			(unlocked yes)
			(layer "F.SilkS")
			(hide yes)
			(effects
				(font
					(size 1.524 1.524)
					(thickness 0.254)
				)
			)
		)
		(sheetname "ZED-F9T")
		(sheetfile "ZED-F9T.kicad_sch")
		(duplicate_pad_numbers_are_jumpers no)
		(fp_line
			(start -0.95 -0.5)
			(end 0.95 -0.5)
			(stroke
				(width 0.1)
				(type solid)
			)
			(layer "F.CrtYd")
		)
		(fp_line
			(start -0.95 0.5)
			(end -0.95 -0.5)
			(stroke
				(width 0.1)
				(type solid)
			)
			(layer "F.CrtYd")
		)
		(fp_line
			(start -0.95 0.5)
			(end 0.95 0.5)
			(stroke
				(width 0.1)
				(type solid)
			)
			(layer "F.CrtYd")
		)
		(fp_line
			(start 0.95 0.5)
			(end 0.95 -0.5)
			(stroke
				(width 0.1)
				(type solid)
			)
			(layer "F.CrtYd")
		)
		(fp_line
			(start -0.5 -0.25)
			(end 0.5 -0.25)
			(stroke
				(width 0.05)
				(type solid)
			)
			(layer "F.Fab")
		)
		(fp_line
			(start -0.5 0.25)
			(end -0.5 -0.25)
			(stroke
				(width 0.05)
				(type solid)
			)
			(layer "F.Fab")
		)
		(fp_line
			(start -0.5 0.25)
			(end 0.5 0.25)
			(stroke
				(width 0.05)
				(type solid)
			)
			(layer "F.Fab")
		)
		(fp_line
			(start 0.5 0.25)
			(end 0.5 -0.25)
			(stroke
				(width 0.05)
				(type solid)
			)
			(layer "F.Fab")
		)
		(fp_text_box "${REFERENCE}"
			(start -1.09004 -0.20727)
			(end 1.09004 0.20726)
			(margins 0 0 0 0)
			(layer "F.Fab")
			(effects
				(font
					(face "Arial")
					(size 0.315 0.315)
					(thickness 0.254)
				)
				(justify top)
			)
			(border no)
			(stroke
				(width 0.1)
				(type default)
			)
			(knockout no)
		)
		(pad "1" smd rect
			(at -0.46 0)
			(size 0.6 0.62)
			(layers "F.Cu" "F.Mask" "F.Paste")
			(net "VCC")
			(solder_mask_margin 0.05)
			(solder_paste_margin 0)
		)
		(pad "2" smd rect
			(at 0.46 0)
			(size 0.6 0.62)
			(layers "F.Cu" "F.Mask" "F.Paste")
			(net "GND")
			(solder_mask_margin 0.05)
			(solder_paste_margin 0)
		)
	)
	(footprint "Vault:FP-0402-L_1_0_0_05-W_0_5-IPC_B"
		(layer "F.Cu")
		(at 133.83201 103.3274 180)
		(property "Reference" "C9"
			(at 1.49491 1.26983 0)
			(unlocked yes)
			(layer "F.SilkS")
			(effects
				(font
					(size 0.8 0.8)
					(thickness 0.15)
				)
			)
		)
		(property "Value" "100nF"
			(at -3.38655 -1.924242 0)
			(unlocked yes)
			(layer "F.SilkS")
			(hide yes)
			(effects
				(font
					(size 1.524 1.524)
					(thickness 0.254)
				)
			)
		)
		(sheetname "Antenna_Supervisor")
		(sheetfile "Antenna_Supervisor.kicad_sch")
		(duplicate_pad_numbers_are_jumpers no)
		(fp_line
			(start 0.73624 0.68623)
			(end -0.73624 0.68623)
			(stroke
				(width 0.2)
				(type solid)
			)
			(layer "F.SilkS")
		)
		(fp_line
			(start 0.73624 -0.68624)
			(end -0.73624 -0.68624)
			(stroke
				(width 0.2)
				(type solid)
			)
			(layer "F.SilkS")
		)
		(fp_line
			(start 0.88624 0.43623)
			(end -0.88624 0.43623)
			(stroke
				(width 0.2)
				(type solid)
			)
			(layer "F.CrtYd")
		)
		(fp_line
			(start 0.88624 -0.43624)
			(end 0.88624 0.43623)
			(stroke
				(width 0.2)
				(type solid)
			)
			(layer "F.CrtYd")
		)
		(fp_line
			(start 0.88624 -0.43624)
			(end -0.88624 -0.43624)
			(stroke
				(width 0.2)
				(type solid)
			)
			(layer "F.CrtYd")
		)
		(fp_line
			(start -0.88624 -0.43624)
			(end -0.88624 0.43623)
			(stroke
				(width 0.2)
				(type solid)
			)
			(layer "F.CrtYd")
		)
		(fp_line
			(start 0.88624 0.43623)
			(end -0.88624 0.43623)
			(stroke
				(width 0.2)
				(type solid)
			)
			(layer "F.Fab")
		)
		(fp_line
			(start 0.88624 -0.43624)
			(end 0.88624 0.43623)
			(stroke
				(width 0.2)
				(type solid)
			)
			(layer "F.Fab")
		)
		(fp_line
			(start 0.88624 -0.43624)
			(end -0.88624 -0.43624)
			(stroke
				(width 0.2)
				(type solid)
			)
			(layer "F.Fab")
		)
		(fp_line
			(start 0.5 0)
			(end -0.5 0)
			(stroke
				(width 0.1)
				(type solid)
			)
			(layer "F.Fab")
		)
		(fp_line
			(start 0 -0.5)
			(end 0 0.49999)
			(stroke
				(width 0.1)
				(type solid)
			)
			(layer "F.Fab")
		)
		(fp_line
			(start -0.88624 -0.43624)
			(end -0.88624 0.43623)
			(stroke
				(width 0.2)
				(type solid)
			)
			(layer "F.Fab")
		)
		(fp_text user "${REFERENCE}"
			(at 0.4572 -1.64587 360)
			(unlocked yes)
			(layer "F.Fab")
			(effects
				(font
					(face "Arial")
					(size 0.63 0.63)
					(thickness 0.1)
				)
				(justify left bottom)
			)
		)
		(pad "1" smd rect
			(at -0.42856 0 180)
			(size 0.61535 0.57247)
			(layers "F.Cu" "F.Mask" "F.Paste")
			(net "VCC")
			(solder_mask_margin 0)
			(solder_paste_margin 0)
		)
		(pad "2" smd rect
			(at 0.42856 0 180)
			(size 0.61535 0.57247)
			(layers "F.Cu" "F.Mask" "F.Paste")
			(net "GND")
			(solder_mask_margin 0)
			(solder_paste_margin 0)
		)
	)
	(footprint "Vault:FP-0402-L_1_0_0_05-W_0_5-IPC_B"
		(layer "F.Cu")
		(at 129.9011 107.2871 180)
		(property "Reference" "C7"
			(at -2.055 -0.02827 0)
			(unlocked yes)
			(layer "F.SilkS")
			(effects
				(font
					(size 0.8 0.8)
					(thickness 0.15)
				)
			)
		)
		(property "Value" "100nF"
			(at -2.95799 -2.352802 0)
			(unlocked yes)
			(layer "F.SilkS")
			(hide yes)
			(effects
				(font
					(size 1.524 1.524)
					(thickness 0.254)
				)
			)
		)
		(sheetname "Antenna_Supervisor")
		(sheetfile "Antenna_Supervisor.kicad_sch")
		(duplicate_pad_numbers_are_jumpers no)
		(fp_line
			(start 0.73623 0.68624)
			(end -0.73624 0.68624)
			(stroke
				(width 0.2)
				(type solid)
			)
			(layer "F.SilkS")
		)
		(fp_line
			(start 0.73623 -0.68624)
			(end -0.73624 -0.68624)
			(stroke
				(width 0.2)
				(type solid)
			)
			(layer "F.SilkS")
		)
		(fp_line
			(start 0.88623 0.43624)
			(end -0.88624 0.43624)
			(stroke
				(width 0.2)
				(type solid)
			)
			(layer "F.CrtYd")
		)
		(fp_line
			(start 0.88623 -0.43624)
			(end 0.88623 0.43624)
			(stroke
				(width 0.2)
				(type solid)
			)
			(layer "F.CrtYd")
		)
		(fp_line
			(start 0.88623 -0.43624)
			(end -0.88624 -0.43624)
			(stroke
				(width 0.2)
				(type solid)
			)
			(layer "F.CrtYd")
		)
		(fp_line
			(start -0.88624 -0.43624)
			(end -0.88624 0.43624)
			(stroke
				(width 0.2)
				(type solid)
			)
			(layer "F.CrtYd")
		)
		(fp_line
			(start 0.88623 0.43624)
			(end -0.88624 0.43624)
			(stroke
				(width 0.2)
				(type solid)
			)
			(layer "F.Fab")
		)
		(fp_line
			(start 0.88623 -0.43624)
			(end 0.88623 0.43624)
			(stroke
				(width 0.2)
				(type solid)
			)
			(layer "F.Fab")
		)
		(fp_line
			(start 0.88623 -0.43624)
			(end -0.88624 -0.43624)
			(stroke
				(width 0.2)
				(type solid)
			)
			(layer "F.Fab")
		)
		(fp_line
			(start 0.5 0)
			(end -0.5 0)
			(stroke
				(width 0.1)
				(type solid)
			)
			(layer "F.Fab")
		)
		(fp_line
			(start 0 -0.5)
			(end 0 0.5)
			(stroke
				(width 0.1)
				(type solid)
			)
			(layer "F.Fab")
		)
		(fp_line
			(start -0.88624 -0.43624)
			(end -0.88624 0.43624)
			(stroke
				(width 0.2)
				(type solid)
			)
			(layer "F.Fab")
		)
		(fp_text user "${REFERENCE}"
			(at -1.2954 -0.37587 360)
			(unlocked yes)
			(layer "F.Fab")
			(effects
				(font
					(face "Arial")
					(size 0.63 0.63)
					(thickness 0.1)
				)
				(justify left bottom)
			)
		)
		(pad "1" smd rect
			(at -0.42856 0 180)
			(size 0.61535 0.57247)
			(layers "F.Cu" "F.Mask" "F.Paste")
			(net "VCC")
			(solder_mask_margin 0)
			(solder_paste_margin 0)
		)
		(pad "2" smd rect
			(at 0.42856 0 180)
			(size 0.61535 0.57247)
			(layers "F.Cu" "F.Mask" "F.Paste")
			(net "GND")
			(solder_mask_margin 0)
			(solder_paste_margin 0)
		)
	)
	(footprint "Vault:FP-RMCF0402-MFG"
		(layer "F.Cu")
		(at 136.0225 103.2739 180)
		(property "Reference" "R13"
			(at -1.013615 1.41953 360)
			(unlocked yes)
			(layer "F.SilkS")
			(effects
				(font
					(size 0.8 0.8)
					(thickness 0.15001)
				)
			)
		)
		(property "Value" "1k"
			(at -2.530602 0.72357 90)
			(unlocked yes)
			(layer "F.SilkS")
			(hide yes)
			(effects
				(font
					(size 1.524 1.524)
					(thickness 0.254)
				)
			)
		)
		(sheetname "Antenna_Supervisor")
		(sheetfile "Antenna_Supervisor.kicad_sch")
		(duplicate_pad_numbers_are_jumpers no)
		(fp_line
			(start 0.55 0.7)
			(end -0.55 0.7)
			(stroke
				(width 0.2)
				(type solid)
			)
			(layer "F.SilkS")
		)
		(fp_line
			(start 0.55 -0.7)
			(end -0.55 -0.7)
			(stroke
				(width 0.2)
				(type solid)
			)
			(layer "F.SilkS")
		)
		(fp_line
			(start 0.85 0.4)
			(end -0.85 0.4)
			(stroke
				(width 0.2)
				(type solid)
			)
			(layer "F.CrtYd")
		)
		(fp_line
			(start 0.85 -0.4)
			(end 0.85 0.4)
			(stroke
				(width 0.2)
				(type solid)
			)
			(layer "F.CrtYd")
		)
		(fp_line
			(start 0.85 -0.4)
			(end -0.85 -0.4)
			(stroke
				(width 0.2)
				(type solid)
			)
			(layer "F.CrtYd")
		)
		(fp_line
			(start -0.85 -0.4)
			(end -0.85 0.4)
			(stroke
				(width 0.2)
				(type solid)
			)
			(layer "F.CrtYd")
		)
		(fp_line
			(start 0.85 0.4)
			(end -0.85 0.4)
			(stroke
				(width 0.2)
				(type solid)
			)
			(layer "F.Fab")
		)
		(fp_line
			(start 0.85 -0.4)
			(end 0.85 0.4)
			(stroke
				(width 0.2)
				(type solid)
			)
			(layer "F.Fab")
		)
		(fp_line
			(start 0.85 -0.4)
			(end -0.85 -0.4)
			(stroke
				(width 0.2)
				(type solid)
			)
			(layer "F.Fab")
		)
		(fp_line
			(start 0.5 0)
			(end -0.5 0)
			(stroke
				(width 0.1)
				(type solid)
			)
			(layer "F.Fab")
		)
		(fp_line
			(start 0 -0.5)
			(end 0 0.5)
			(stroke
				(width 0.1)
				(type solid)
			)
			(layer "F.Fab")
		)
		(fp_line
			(start -0.85 -0.4)
			(end -0.85 0.4)
			(stroke
				(width 0.2)
				(type solid)
			)
			(layer "F.Fab")
		)
		(fp_text user "${REFERENCE}"
			(at -0.00001 0.09556 180)
			(unlocked yes)
			(layer "F.Fab")
			(effects
				(font
					(face "Arial")
					(size 0.63 0.63)
					(thickness 0.1)
				)
				(justify left bottom)
			)
		)
		(pad "1" smd rect
			(at -0.5 0 180)
			(size 0.5 0.6)
			(layers "F.Cu" "F.Mask" "F.Paste")
			(net "ANT_DET")
			(solder_mask_margin 0)
			(solder_paste_margin 0)
		)
		(pad "2" smd rect
			(at 0.5 0 180)
			(size 0.5 0.6)
			(layers "F.Cu" "F.Mask" "F.Paste")
			(net "VCC")
			(solder_mask_margin 0)
			(solder_paste_margin 0)
		)
	)
	(footprint "Vault:FP-RMCF0402-MFG"
		(layer "F.Cu")
		(at 135.9971 108.6333 180)
		(property "Reference" "R14"
			(at -0.429415 -1.57767 360)
			(unlocked yes)
			(layer "F.SilkS")
			(effects
				(font
					(size 0.8 0.8)
					(thickness 0.15001)
				)
			)
		)
		(property "Value" "1k"
			(at -2.530602 0.72357 90)
			(unlocked yes)
			(layer "F.SilkS")
			(hide yes)
			(effects
				(font
					(size 1.524 1.524)
					(thickness 0.254)
				)
			)
		)
		(sheetname "Antenna_Supervisor")
		(sheetfile "Antenna_Supervisor.kicad_sch")
		(duplicate_pad_numbers_are_jumpers no)
		(fp_line
			(start 0.55 0.7)
			(end -0.55 0.7)
			(stroke
				(width 0.2)
				(type solid)
			)
			(layer "F.SilkS")
		)
		(fp_line
			(start 0.55 -0.7)
			(end -0.55 -0.7)
			(stroke
				(width 0.2)
				(type solid)
			)
			(layer "F.SilkS")
		)
		(fp_line
			(start 0.85 0.4)
			(end -0.85 0.4)
			(stroke
				(width 0.2)
				(type solid)
			)
			(layer "F.CrtYd")
		)
		(fp_line
			(start 0.85 -0.4)
			(end 0.85 0.4)
			(stroke
				(width 0.2)
				(type solid)
			)
			(layer "F.CrtYd")
		)
		(fp_line
			(start 0.85 -0.4)
			(end -0.85 -0.4)
			(stroke
				(width 0.2)
				(type solid)
			)
			(layer "F.CrtYd")
		)
		(fp_line
			(start -0.85 -0.4)
			(end -0.85 0.4)
			(stroke
				(width 0.2)
				(type solid)
			)
			(layer "F.CrtYd")
		)
		(fp_line
			(start 0.85 0.4)
			(end -0.85 0.4)
			(stroke
				(width 0.2)
				(type solid)
			)
			(layer "F.Fab")
		)
		(fp_line
			(start 0.85 -0.4)
			(end 0.85 0.4)
			(stroke
				(width 0.2)
				(type solid)
			)
			(layer "F.Fab")
		)
		(fp_line
			(start 0.85 -0.4)
			(end -0.85 -0.4)
			(stroke
				(width 0.2)
				(type solid)
			)
			(layer "F.Fab")
		)
		(fp_line
			(start 0.5 0)
			(end -0.5 0)
			(stroke
				(width 0.1)
				(type solid)
			)
			(layer "F.Fab")
		)
		(fp_line
			(start 0 -0.5)
			(end 0 0.5)
			(stroke
				(width 0.1)
				(type solid)
			)
			(layer "F.Fab")
		)
		(fp_line
			(start -0.85 -0.4)
			(end -0.85 0.4)
			(stroke
				(width 0.2)
				(type solid)
			)
			(layer "F.Fab")
		)
		(fp_text user "${REFERENCE}"
			(at -0.00001 0.10711 180)
			(unlocked yes)
			(layer "F.Fab")
			(effects
				(font
					(face "Arial")
					(size 0.63 0.63)
					(thickness 0.1)
				)
				(justify left bottom)
			)
		)
		(pad "1" smd rect
			(at -0.5 0 180)
			(size 0.5 0.6)
			(layers "F.Cu" "F.Mask" "F.Paste")
			(net "ANT_SHORT_N")
			(solder_mask_margin 0)
			(solder_paste_margin 0)
		)
		(pad "2" smd rect
			(at 0.5 0 180)
			(size 0.5 0.6)
			(layers "F.Cu" "F.Mask" "F.Paste")
			(net "VCC")
			(solder_mask_margin 0)
			(solder_paste_margin 0)
		)
	)
	(footprint "Vault:FP-RMCF0402-IPC_C"
		(layer "F.Cu")
		(at 130.6631 116.25835)
		(property "Reference" "R9"
			(at -1.7296 0.20607 0)
			(unlocked yes)
			(layer "F.SilkS")
			(effects
				(font
					(size 0.8 0.8)
					(thickness 0.15)
				)
			)
		)
		(property "Value" "100k"
			(at 2.06928 2.225802 0)
			(unlocked yes)
			(layer "F.SilkS")
			(hide yes)
			(effects
				(font
					(size 1.524 1.524)
					(thickness 0.254)
				)
			)
		)
		(sheetname "Antenna_Supervisor")
		(sheetfile "Antenna_Supervisor.kicad_sch")
		(duplicate_pad_numbers_are_jumpers no)
		(fp_line
			(start -0.65606 -0.675)
			(end 0.65607 -0.675)
			(stroke
				(width 0.2)
				(type solid)
			)
			(layer "F.SilkS")
		)
		(fp_line
			(start -0.65606 0.675)
			(end 0.65607 0.675)
			(stroke
				(width 0.2)
				(type solid)
			)
			(layer "F.SilkS")
		)
		(fp_line
			(start -0.75606 -0.375)
			(end 0.75607 -0.375)
			(stroke
				(width 0.2)
				(type solid)
			)
			(layer "F.CrtYd")
		)
		(fp_line
			(start -0.75606 0.375)
			(end -0.75606 -0.375)
			(stroke
				(width 0.2)
				(type solid)
			)
			(layer "F.CrtYd")
		)
		(fp_line
			(start -0.75606 0.375)
			(end 0.75607 0.375)
			(stroke
				(width 0.2)
				(type solid)
			)
			(layer "F.CrtYd")
		)
		(fp_line
			(start 0.75607 0.375)
			(end 0.75607 -0.375)
			(stroke
				(width 0.2)
				(type solid)
			)
			(layer "F.CrtYd")
		)
		(fp_line
			(start -0.75606 -0.375)
			(end 0.75607 -0.375)
			(stroke
				(width 0.2)
				(type solid)
			)
			(layer "F.Fab")
		)
		(fp_line
			(start -0.75606 0.375)
			(end -0.75606 -0.375)
			(stroke
				(width 0.2)
				(type solid)
			)
			(layer "F.Fab")
		)
		(fp_line
			(start -0.75606 0.375)
			(end 0.75607 0.375)
			(stroke
				(width 0.2)
				(type solid)
			)
			(layer "F.Fab")
		)
		(fp_line
			(start -0.5 0)
			(end 0.5 0)
			(stroke
				(width 0.1)
				(type solid)
			)
			(layer "F.Fab")
		)
		(fp_line
			(start 0 0.5)
			(end 0 -0.5)
			(stroke
				(width 0.1)
				(type solid)
			)
			(layer "F.Fab")
		)
		(fp_line
			(start 0.75607 0.375)
			(end 0.75607 -0.375)
			(stroke
				(width 0.2)
				(type solid)
			)
			(layer "F.Fab")
		)
		(fp_text user "${REFERENCE}"
			(at -0.00001 0.09648 360)
			(unlocked yes)
			(layer "F.Fab")
			(effects
				(font
					(face "Arial")
					(size 0.63 0.63)
					(thickness 0.1)
				)
				(justify left bottom)
			)
		)
		(pad "1" smd rect
			(at -0.36553 0)
			(size 0.58106 0.47247)
			(layers "F.Cu" "F.Mask" "F.Paste")
			(net "NetQ1_1")
			(solder_mask_margin 0)
			(solder_paste_margin 0)
		)
		(pad "2" smd rect
			(at 0.36554 0)
			(size 0.58106 0.47247)
			(layers "F.Cu" "F.Mask" "F.Paste")
			(net "VCC_ANT")
			(solder_mask_margin 0)
			(solder_paste_margin 0)
		)
	)
	(footprint "Vault:FP-RMCF0402-MFG"
		(layer "F.Cu")
		(at 170.8205 103.9597 90)
		(property "Reference" "R2"
			(at 2.35981 0.07907 90)
			(unlocked yes)
			(layer "F.SilkS")
			(effects
				(font
					(size 0.8 0.8)
					(thickness 0.15001)
				)
			)
		)
		(property "Value" "1k"
			(at 0.57117 2.378202 90)
			(unlocked yes)
			(layer "F.SilkS")
			(hide yes)
			(effects
				(font
					(size 1.524 1.524)
					(thickness 0.254)
				)
			)
		)
		(sheetname "ZED-F9T")
		(sheetfile "ZED-F9T.kicad_sch")
		(duplicate_pad_numbers_are_jumpers no)
		(fp_line
			(start -0.55 -0.7)
			(end 0.55 -0.7)
			(stroke
				(width 0.2)
				(type solid)
			)
			(layer "F.SilkS")
		)
		(fp_line
			(start -0.55 0.7)
			(end 0.55 0.7)
			(stroke
				(width 0.2)
				(type solid)
			)
			(layer "F.SilkS")
		)
		(fp_line
			(start 0.85 -0.4)
			(end 0.85 0.4)
			(stroke
				(width 0.2)
				(type solid)
			)
			(layer "F.CrtYd")
		)
		(fp_line
			(start -0.85 -0.4)
			(end 0.85 -0.4)
			(stroke
				(width 0.2)
				(type solid)
			)
			(layer "F.CrtYd")
		)
		(fp_line
			(start -0.85 -0.4)
			(end -0.85 0.4)
			(stroke
				(width 0.2)
				(type solid)
			)
			(layer "F.CrtYd")
		)
		(fp_line
			(start -0.85 0.4)
			(end 0.85 0.4)
			(stroke
				(width 0.2)
				(type solid)
			)
			(layer "F.CrtYd")
		)
		(fp_line
			(start 0 -0.5)
			(end 0 0.5)
			(stroke
				(width 0.1)
				(type solid)
			)
			(layer "F.Fab")
		)
		(fp_line
			(start 0.85 -0.4)
			(end 0.85 0.4)
			(stroke
				(width 0.2)
				(type solid)
			)
			(layer "F.Fab")
		)
		(fp_line
			(start -0.85 -0.4)
			(end 0.85 -0.4)
			(stroke
				(width 0.2)
				(type solid)
			)
			(layer "F.Fab")
		)
		(fp_line
			(start -0.85 -0.4)
			(end -0.85 0.4)
			(stroke
				(width 0.2)
				(type solid)
			)
			(layer "F.Fab")
		)
		(fp_line
			(start -0.5 0)
			(end 0.5 0)
			(stroke
				(width 0.1)
				(type solid)
			)
			(layer "F.Fab")
		)
		(fp_line
			(start -0.85 0.4)
			(end 0.85 0.4)
			(stroke
				(width 0.2)
				(type solid)
			)
			(layer "F.Fab")
		)
		(fp_text user "${REFERENCE}"
			(at -0.00001 0.10711 90)
			(unlocked yes)
			(layer "F.Fab")
			(effects
				(font
					(face "Arial")
					(size 0.63 0.63)
					(thickness 0.1)
				)
				(justify left bottom)
			)
		)
		(pad "1" smd rect
			(at -0.5 0 90)
			(size 0.5 0.6)
			(layers "F.Cu" "F.Mask" "F.Paste")
			(net "RXD")
			(solder_mask_margin 0)
			(solder_paste_margin 0)
		)
		(pad "2" smd rect
			(at 0.5 0 90)
			(size 0.5 0.6)
			(layers "F.Cu" "F.Mask" "F.Paste")
			(net "VCC")
			(solder_mask_margin 0)
			(solder_paste_margin 0)
		)
	)
	(footprint "Vault:FP-0402-L_1_0_0_05-W_0_5-IPC_B"
		(layer "F.Cu")
		(at 134.3461 101.1657 180)
		(property "Reference" "C8"
			(at -0.15 1.49573 0)
			(unlocked yes)
			(layer "F.SilkS")
			(effects
				(font
					(size 0.8 0.8)
					(thickness 0.15)
				)
			)
		)
		(property "Value" "100nF"
			(at -2.95799 -2.352802 0)
			(unlocked yes)
			(layer "F.SilkS")
			(hide yes)
			(effects
				(font
					(size 1.524 1.524)
					(thickness 0.254)
				)
			)
		)
		(sheetname "Antenna_Supervisor")
		(sheetfile "Antenna_Supervisor.kicad_sch")
		(duplicate_pad_numbers_are_jumpers no)
		(fp_line
			(start 0.73623 0.68624)
			(end -0.73624 0.68624)
			(stroke
				(width 0.2)
				(type solid)
			)
			(layer "F.SilkS")
		)
		(fp_line
			(start 0.73623 -0.68624)
			(end -0.73624 -0.68624)
			(stroke
				(width 0.2)
				(type solid)
			)
			(layer "F.SilkS")
		)
		(fp_line
			(start 0.88623 0.43624)
			(end -0.88624 0.43624)
			(stroke
				(width 0.2)
				(type solid)
			)
			(layer "F.CrtYd")
		)
		(fp_line
			(start 0.88623 -0.43624)
			(end 0.88623 0.43624)
			(stroke
				(width 0.2)
				(type solid)
			)
			(layer "F.CrtYd")
		)
		(fp_line
			(start 0.88623 -0.43624)
			(end -0.88624 -0.43624)
			(stroke
				(width 0.2)
				(type solid)
			)
			(layer "F.CrtYd")
		)
		(fp_line
			(start -0.88624 -0.43624)
			(end -0.88624 0.43624)
			(stroke
				(width 0.2)
				(type solid)
			)
			(layer "F.CrtYd")
		)
		(fp_line
			(start 0.88623 0.43624)
			(end -0.88624 0.43624)
			(stroke
				(width 0.2)
				(type solid)
			)
			(layer "F.Fab")
		)
		(fp_line
			(start 0.88623 -0.43624)
			(end 0.88623 0.43624)
			(stroke
				(width 0.2)
				(type solid)
			)
			(layer "F.Fab")
		)
		(fp_line
			(start 0.88623 -0.43624)
			(end -0.88624 -0.43624)
			(stroke
				(width 0.2)
				(type solid)
			)
			(layer "F.Fab")
		)
		(fp_line
			(start 0.5 0)
			(end -0.5 0)
			(stroke
				(width 0.1)
				(type solid)
			)
			(layer "F.Fab")
		)
		(fp_line
			(start 0 -0.5)
			(end 0 0.5)
			(stroke
				(width 0.1)
				(type solid)
			)
			(layer "F.Fab")
		)
		(fp_line
			(start -0.88624 -0.43624)
			(end -0.88624 0.43624)
			(stroke
				(width 0.2)
				(type solid)
			)
			(layer "F.Fab")
		)
		(fp_text user "${REFERENCE}"
			(at 0.5842 0.94493 360)
			(unlocked yes)
			(layer "F.Fab")
			(effects
				(font
					(face "Arial")
					(size 0.63 0.63)
					(thickness 0.1)
				)
				(justify left bottom)
			)
		)
		(pad "1" smd rect
			(at -0.42856 0 180)
			(size 0.61535 0.57247)
			(layers "F.Cu" "F.Mask" "F.Paste")
			(net "RF_IN")
			(solder_mask_margin 0)
			(solder_paste_margin 0)
		)
		(pad "2" smd rect
			(at 0.42856 0 180)
			(size 0.61535 0.57247)
			(layers "F.Cu" "F.Mask" "F.Paste")
			(net "RF_ANT")
			(solder_mask_margin 0)
			(solder_paste_margin 0)
		)
	)
	(footprint "Vault:FP-RMCF0402-IPC_C"
		(layer "F.Cu")
		(at 132.4411 109.1921 180)
		(property "Reference" "R11"
			(at -0.632605 -1.55227 0)
			(unlocked yes)
			(layer "F.SilkS")
			(effects
				(font
					(size 0.8 0.8)
					(thickness 0.15)
				)
			)
		)
		(property "Value" "100k"
			(at -2.19628 -2.352802 0)
			(unlocked yes)
			(layer "F.SilkS")
			(hide yes)
			(effects
				(font
					(size 1.524 1.524)
					(thickness 0.254)
				)
			)
		)
		(sheetname "Antenna_Supervisor")
		(sheetfile "Antenna_Supervisor.kicad_sch")
		(duplicate_pad_numbers_are_jumpers no)
		(fp_line
			(start 0.65606 0.675)
			(end -0.65607 0.675)
			(stroke
				(width 0.2)
				(type solid)
			)
			(layer "F.SilkS")
		)
		(fp_line
			(start 0.65606 -0.675)
			(end -0.65607 -0.675)
			(stroke
				(width 0.2)
				(type solid)
			)
			(layer "F.SilkS")
		)
		(fp_line
			(start 0.75606 0.375)
			(end -0.75607 0.375)
			(stroke
				(width 0.2)
				(type solid)
			)
			(layer "F.CrtYd")
		)
		(fp_line
			(start 0.75606 -0.375)
			(end 0.75606 0.375)
			(stroke
				(width 0.2)
				(type solid)
			)
			(layer "F.CrtYd")
		)
		(fp_line
			(start 0.75606 -0.375)
			(end -0.75607 -0.375)
			(stroke
				(width 0.2)
				(type solid)
			)
			(layer "F.CrtYd")
		)
		(fp_line
			(start -0.75607 -0.375)
			(end -0.75607 0.375)
			(stroke
				(width 0.2)
				(type solid)
			)
			(layer "F.CrtYd")
		)
		(fp_line
			(start 0.75606 0.375)
			(end -0.75607 0.375)
			(stroke
				(width 0.2)
				(type solid)
			)
			(layer "F.Fab")
		)
		(fp_line
			(start 0.75606 -0.375)
			(end 0.75606 0.375)
			(stroke
				(width 0.2)
				(type solid)
			)
			(layer "F.Fab")
		)
		(fp_line
			(start 0.75606 -0.375)
			(end -0.75607 -0.375)
			(stroke
				(width 0.2)
				(type solid)
			)
			(layer "F.Fab")
		)
		(fp_line
			(start 0.5 0)
			(end -0.5 0)
			(stroke
				(width 0.1)
				(type solid)
			)
			(layer "F.Fab")
		)
		(fp_line
			(start 0 -0.5)
			(end 0 0.5)
			(stroke
				(width 0.1)
				(type solid)
			)
			(layer "F.Fab")
		)
		(fp_line
			(start -0.75607 -0.375)
			(end -0.75607 0.375)
			(stroke
				(width 0.2)
				(type solid)
			)
			(layer "F.Fab")
		)
		(fp_text user "${REFERENCE}"
			(at 0.4826 -1.9105 360)
			(unlocked yes)
			(layer "F.Fab")
			(effects
				(font
					(face "Arial")
					(size 0.63 0.63)
					(thickness 0.1)
				)
				(justify left bottom)
			)
		)
		(pad "1" smd rect
			(at -0.36554 0 180)
			(size 0.58106 0.47247)
			(layers "F.Cu" "F.Mask" "F.Paste")
			(net "GND")
			(solder_mask_margin 0)
			(solder_paste_margin 0)
		)
		(pad "2" smd rect
			(at 0.36553 0 180)
			(size 0.58106 0.47247)
			(layers "F.Cu" "F.Mask" "F.Paste")
			(net "NetR10_1")
			(solder_mask_margin 0)
			(solder_paste_margin 0)
		)
	)
	(footprint "Vault:DCU0008A_N"
		(layer "F.Cu")
		(at 134.7271 106.0679)
		(property "Reference" "U3"
			(at -0.4088 2.00947 0)
			(unlocked yes)
			(layer "F.SilkS")
			(effects
				(font
					(size 0.8 0.8)
					(thickness 0.15)
				)
			)
		)
		(property "Value" "SN74LVC3G07DCUR"
			(at 9.432485 2.911602 0)
			(unlocked yes)
			(layer "F.SilkS")
			(hide yes)
			(effects
				(font
					(size 1.524 1.524)
					(thickness 0.254)
				)
			)
		)
		(sheetname "Antenna_Supervisor")
		(sheetfile "Antenna_Supervisor.kicad_sch")
		(duplicate_pad_numbers_are_jumpers no)
		(fp_line
			(start -0.8 -1.05)
			(end 0.8 -1.05)
			(stroke
				(width 0.2)
				(type solid)
			)
			(layer "F.SilkS")
		)
		(fp_line
			(start -0.8 1.05)
			(end -0.8 -1.05)
			(stroke
				(width 0.2)
				(type solid)
			)
			(layer "F.SilkS")
		)
		(fp_line
			(start -0.8 1.05)
			(end 0.8 1.05)
			(stroke
				(width 0.2)
				(type solid)
			)
			(layer "F.SilkS")
		)
		(fp_line
			(start 0.8 1.05)
			(end 0.8 -1.05)
			(stroke
				(width 0.2)
				(type solid)
			)
			(layer "F.SilkS")
		)
		(fp_circle
			(center -1.6 -1.45)
			(end -1.6 -1.575)
			(stroke
				(width 0.25)
				(type solid)
			)
			(fill no)
			(layer "F.SilkS")
		)
		(fp_line
			(start -2.225 -1.3)
			(end 2.225 -1.3)
			(stroke
				(width 0.05)
				(type solid)
			)
			(layer "F.CrtYd")
		)
		(fp_line
			(start -2.225 1.3)
			(end -2.225 -1.3)
			(stroke
				(width 0.05)
				(type solid)
			)
			(layer "F.CrtYd")
		)
		(fp_line
			(start -2.225 1.3)
			(end 2.225 1.3)
			(stroke
				(width 0.05)
				(type solid)
			)
			(layer "F.CrtYd")
		)
		(fp_line
			(start -0.5 0)
			(end 0.5 0)
			(stroke
				(width 0.1)
				(type solid)
			)
			(layer "F.CrtYd")
		)
		(fp_line
			(start 0 0.5)
			(end 0 -0.5)
			(stroke
				(width 0.1)
				(type solid)
			)
			(layer "F.CrtYd")
		)
		(fp_line
			(start 2.225 1.3)
			(end 2.225 -1.3)
			(stroke
				(width 0.05)
				(type solid)
			)
			(layer "F.CrtYd")
		)
		(pad "1" smd roundrect
			(at -1.6 -0.75 90)
			(size 0.3 0.8)
			(layers "F.Cu" "F.Mask" "F.Paste")
			(roundrect_rratio 0.165)
			(net "NetU3_1")
		)
		(pad "2" smd roundrect
			(at -1.6 -0.25 90)
			(size 0.3 0.8)
			(layers "F.Cu" "F.Mask" "F.Paste")
			(roundrect_rratio 0.165)
			(net "NetQ1_1")
		)
		(pad "3" smd roundrect
			(at -1.6 0.25 90)
			(size 0.3 0.8)
			(layers "F.Cu" "F.Mask" "F.Paste")
			(roundrect_rratio 0.165)
			(net "NetC10_1")
		)
		(pad "4" smd roundrect
			(at -1.6 0.75 90)
			(size 0.3 0.8)
			(layers "F.Cu" "F.Mask" "F.Paste")
			(roundrect_rratio 0.165)
			(net "GND")
		)
		(pad "5" smd roundrect
			(at 1.6 0.75 90)
			(size 0.3 0.8)
			(layers "F.Cu" "F.Mask" "F.Paste")
			(roundrect_rratio 0.165)
			(net "ANT_SHORT_N")
		)
		(pad "6" smd roundrect
			(at 1.6 0.25 90)
			(size 0.3 0.8)
			(layers "F.Cu" "F.Mask" "F.Paste")
			(roundrect_rratio 0.165)
			(net "ANT_OFF")
		)
		(pad "7" smd roundrect
			(at 1.6 -0.25 90)
			(size 0.3 0.8)
			(layers "F.Cu" "F.Mask" "F.Paste")
			(roundrect_rratio 0.165)
			(net "ANT_DET")
		)
		(pad "8" smd roundrect
			(at 1.6 -0.75 90)
			(size 0.3 0.8)
			(layers "F.Cu" "F.Mask" "F.Paste")
			(roundrect_rratio 0.165)
			(net "VCC")
		)
	)
	(footprint "Vault:CAPC1005X055N"
		(layer "F.Cu")
		(at 156.4441 104.2391)
		(property "Reference" "C4"
			(at 2.055 0.02827 0)
			(unlocked yes)
			(layer "F.SilkS")
			(effects
				(font
					(size 0.8 0.8)
					(thickness 0.15)
				)
			)
		)
		(property "Value" "Murata_GRM155R61E105KA12D"
			(at 17.863025 2.073402 0)
			(unlocked yes)
			(layer "F.SilkS")
			(hide yes)
			(effects
				(font
					(size 1.524 1.524)
					(thickness 0.254)
				)
			)
		)
		(sheetname "ZED-F9T")
		(sheetfile "ZED-F9T.kicad_sch")
		(duplicate_pad_numbers_are_jumpers no)
		(fp_line
			(start -0.95 -0.5)
			(end 0.95 -0.5)
			(stroke
				(width 0.1)
				(type solid)
			)
			(layer "F.CrtYd")
		)
		(fp_line
			(start -0.95 0.5)
			(end -0.95 -0.5)
			(stroke
				(width 0.1)
				(type solid)
			)
			(layer "F.CrtYd")
		)
		(fp_line
			(start -0.95 0.5)
			(end 0.95 0.5)
			(stroke
				(width 0.1)
				(type solid)
			)
			(layer "F.CrtYd")
		)
		(fp_line
			(start 0.95 0.5)
			(end 0.95 -0.5)
			(stroke
				(width 0.1)
				(type solid)
			)
			(layer "F.CrtYd")
		)
		(fp_line
			(start -0.5 -0.25)
			(end 0.5 -0.25)
			(stroke
				(width 0.05)
				(type solid)
			)
			(layer "F.Fab")
		)
		(fp_line
			(start -0.5 0.25)
			(end -0.5 -0.25)
			(stroke
				(width 0.05)
				(type solid)
			)
			(layer "F.Fab")
		)
		(fp_line
			(start -0.5 0.25)
			(end 0.5 0.25)
			(stroke
				(width 0.05)
				(type solid)
			)
			(layer "F.Fab")
		)
		(fp_line
			(start 0.5 0.25)
			(end 0.5 -0.25)
			(stroke
				(width 0.05)
				(type solid)
			)
			(layer "F.Fab")
		)
		(fp_text_box "${REFERENCE}"
			(start -1.09004 -0.20727)
			(end 1.09004 0.20726)
			(margins 0 0 0 0)
			(layer "F.Fab")
			(effects
				(font
					(face "Arial")
					(size 0.315 0.315)
					(thickness 0.254)
				)
				(justify top)
			)
			(border no)
			(stroke
				(width 0.1)
				(type default)
			)
			(knockout no)
		)
		(pad "1" smd rect
			(at -0.46 0)
			(size 0.6 0.62)
			(layers "F.Cu" "F.Mask" "F.Paste")
			(net "VCC")
			(solder_mask_margin 0.05)
			(solder_paste_margin 0)
		)
		(pad "2" smd rect
			(at 0.46 0)
			(size 0.6 0.62)
			(layers "F.Cu" "F.Mask" "F.Paste")
			(net "GND")
			(solder_mask_margin 0.05)
			(solder_paste_margin 0)
		)
	)
	(footprint "Vault:FP-RMCF0402-IPC_C"
		(layer "F.Cu")
		(at 167.7807 117.55363 -90)
		(property "Reference" "R8"
			(at 1.54734 -0.1418 0)
			(unlocked yes)
			(layer "F.SilkS")
			(effects
				(font
					(size 0.8 0.8)
					(thickness 0.15)
				)
			)
		)
		(property "Value" "10k"
			(at 2.352802 -1.434525 0)
			(unlocked yes)
			(layer "F.SilkS")
			(hide yes)
			(effects
				(font
					(size 1.524 1.524)
					(thickness 0.254)
				)
			)
		)
		(sheetname "ZED-F9T")
		(sheetfile "ZED-F9T.kicad_sch")
		(duplicate_pad_numbers_are_jumpers no)
		(fp_line
			(start 0.65607 0.675)
			(end -0.65607 0.675)
			(stroke
				(width 0.2)
				(type solid)
			)
			(layer "F.SilkS")
		)
		(fp_line
			(start 0.65607 -0.675)
			(end -0.65607 -0.675)
			(stroke
				(width 0.2)
				(type solid)
			)
			(layer "F.SilkS")
		)
		(fp_line
			(start -0.75606 0.375)
			(end -0.75606 -0.375)
			(stroke
				(width 0.2)
				(type solid)
			)
			(layer "F.CrtYd")
		)
		(fp_line
			(start 0.75607 0.375)
			(end -0.75606 0.375)
			(stroke
				(width 0.2)
				(type solid)
			)
			(layer "F.CrtYd")
		)
		(fp_line
			(start 0.75607 0.375)
			(end 0.75607 -0.375)
			(stroke
				(width 0.2)
				(type solid)
			)
			(layer "F.CrtYd")
		)
		(fp_line
			(start 0.75607 -0.375)
			(end -0.75606 -0.375)
			(stroke
				(width 0.2)
				(type solid)
			)
			(layer "F.CrtYd")
		)
		(fp_line
			(start 0 0.5)
			(end 0 -0.5)
			(stroke
				(width 0.1)
				(type solid)
			)
			(layer "F.Fab")
		)
		(fp_line
			(start -0.75606 0.375)
			(end -0.75606 -0.375)
			(stroke
				(width 0.2)
				(type solid)
			)
			(layer "F.Fab")
		)
		(fp_line
			(start 0.75607 0.375)
			(end -0.75606 0.375)
			(stroke
				(width 0.2)
				(type solid)
			)
			(layer "F.Fab")
		)
		(fp_line
			(start 0.75607 0.375)
			(end 0.75607 -0.375)
			(stroke
				(width 0.2)
				(type solid)
			)
			(layer "F.Fab")
		)
		(fp_line
			(start 0.5 0)
			(end -0.5 0)
			(stroke
				(width 0.1)
				(type solid)
			)
			(layer "F.Fab")
		)
		(fp_line
			(start 0.75607 -0.375)
			(end -0.75606 -0.375)
			(stroke
				(width 0.2)
				(type solid)
			)
			(layer "F.Fab")
		)
		(fp_text user "${REFERENCE}"
			(at -0.00001 0.09648 270)
			(unlocked yes)
			(layer "F.Fab")
			(effects
				(font
					(face "Arial")
					(size 0.63 0.63)
					(thickness 0.1)
				)
				(justify left bottom)
			)
		)
		(pad "1" smd rect
			(at -0.36553 0 270)
			(size 0.58106 0.47247)
			(layers "F.Cu" "F.Mask" "F.Paste")
			(net "GND")
			(solder_mask_margin 0)
			(solder_paste_margin 0)
		)
		(pad "2" smd rect
			(at 0.36554 0 270)
			(size 0.58106 0.47247)
			(layers "F.Cu" "F.Mask" "F.Paste")
			(net "NetDS3_K")
			(solder_mask_margin 0)
			(solder_paste_margin 0)
		)
	)
	(footprint "Vault:LEDS160X80X110-2N_LXFM0603-GR"
		(layer "F.Cu")
		(at 165.7577 116.6597 90)
		(property "Reference" "DS2"
			(at 2.77425 0.62377 0)
			(unlocked yes)
			(layer "F.SilkS")
			(effects
				(font
					(size 0.8 0.8)
					(thickness 0.15)
				)
			)
		)
		(property "Value" "Lumex_SML-LXFM0603SUGCTR"
			(at -3.318002 17.78687 0)
			(unlocked yes)
			(layer "F.SilkS")
			(hide yes)
			(effects
				(font
					(size 1.524 1.524)
					(thickness 0.254)
				)
			)
		)
		(sheetname "ZED-F9T")
		(sheetfile "ZED-F9T.kicad_sch")
		(duplicate_pad_numbers_are_jumpers no)
		(fp_line
			(start -1.6 -0.3)
			(end -1.6 0.3)
			(stroke
				(width 0.1)
				(type solid)
			)
			(layer "F.SilkS")
		)
		(fp_line
			(start 1.7 -0.7)
			(end 1.7 0.7)
			(stroke
				(width 0.1)
				(type solid)
			)
			(layer "F.CrtYd")
		)
		(fp_line
			(start -1.7 -0.7)
			(end 1.7 -0.7)
			(stroke
				(width 0.1)
				(type solid)
			)
			(layer "F.CrtYd")
		)
		(fp_line
			(start -1.7 -0.7)
			(end -1.7 0.7)
			(stroke
				(width 0.1)
				(type solid)
			)
			(layer "F.CrtYd")
		)
		(fp_line
			(start -1.7 0.7)
			(end 1.7 0.7)
			(stroke
				(width 0.1)
				(type solid)
			)
			(layer "F.CrtYd")
		)
		(fp_line
			(start 0.80017 -0.40012)
			(end 0.80017 0.39984)
			(stroke
				(width 0.05)
				(type solid)
			)
			(layer "F.Fab")
		)
		(fp_line
			(start -0.79991 -0.40012)
			(end 0.80017 -0.40012)
			(stroke
				(width 0.05)
				(type solid)
			)
			(layer "F.Fab")
		)
		(fp_line
			(start -0.79991 -0.40012)
			(end -0.79991 0.39984)
			(stroke
				(width 0.05)
				(type solid)
			)
			(layer "F.Fab")
		)
		(fp_line
			(start -0.1 -0.3)
			(end -0.1 0.3)
			(stroke
				(width 0.05)
				(type solid)
			)
			(layer "F.Fab")
		)
		(fp_line
			(start 0.1 -0.2)
			(end -0.1 0)
			(stroke
				(width 0.05)
				(type solid)
			)
			(layer "F.Fab")
		)
		(fp_line
			(start 0.1 -0.2)
			(end 0.1 0.2)
			(stroke
				(width 0.05)
				(type solid)
			)
			(layer "F.Fab")
		)
		(fp_line
			(start -0.1 0)
			(end 0.1 0.2)
			(stroke
				(width 0.05)
				(type solid)
			)
			(layer "F.Fab")
		)
		(fp_line
			(start -0.79991 0.39984)
			(end 0.80017 0.39984)
			(stroke
				(width 0.05)
				(type solid)
			)
			(layer "F.Fab")
		)
		(fp_text_box "${REFERENCE}"
			(start -2.76576 -0.52568)
			(end 2.76577 0.52568)
			(margins 0 0 0 0)
			(layer "F.Fab")
			(effects
				(font
					(face "Arial")
					(size 0.8001 0.8001)
					(thickness 0.254)
				)
				(justify top)
			)
			(border no)
			(stroke
				(width 0.1)
				(type default)
			)
			(knockout no)
		)
		(pad "A" smd rect
			(at 0.825 0 90)
			(size 0.8 0.8)
			(layers "F.Cu" "F.Mask" "F.Paste")
			(net "VCC")
			(solder_mask_margin 0.05)
			(solder_paste_margin 0)
		)
		(pad "K" smd rect
			(at -0.825 0 90)
			(size 0.8 0.8)
			(layers "F.Cu" "F.Mask" "F.Paste")
			(net "NetDS2_K")
			(solder_mask_margin 0.05)
			(solder_paste_margin 0)
		)
	)
	(footprint "Vault:TP001V_SMT_100DIA"
		(layer "F.Cu")
		(at 151.9991 95.0951 90)
		(property "Reference" "TP4"
			(at 2.563 0.23147 90)
			(unlocked yes)
			(layer "F.SilkS")
			(effects
				(font
					(size 0.8 0.8)
					(thickness 0.15)
				)
			)
		)
		(property "Value" "SMT_100DIA"
			(at -2.124202 7.0716 0)
			(unlocked yes)
			(layer "F.SilkS")
			(hide yes)
			(effects
				(font
					(size 1.524 1.524)
					(thickness 0.254)
				)
			)
		)
		(sheetname "ZED-F9T")
		(sheetfile "ZED-F9T.kicad_sch")
		(duplicate_pad_numbers_are_jumpers no)
		(pad "1" smd circle
			(at 0 0 90)
			(size 1 1)
			(layers "F.Cu" "F.Mask" "F.Paste")
			(net "NetTP4_1")
			(solder_mask_margin 0.05)
			(solder_paste_margin 0)
			(thermal_bridge_angle 90)
		)
	)
	(footprint "Vault:DCU0008A_N"
		(layer "F.Cu")
		(at 165.8675 108.2523 -90)
		(property "Reference" "U2"
			(at -3.28225 0.3603 0)
			(unlocked yes)
			(layer "F.SilkS")
			(effects
				(font
					(size 0.8 0.8)
					(thickness 0.15)
				)
			)
		)
		(property "Value" "SN74LVC3G07DCUR"
			(at 2.530602 -9.813485 0)
			(unlocked yes)
			(layer "F.SilkS")
			(hide yes)
			(effects
				(font
					(size 1.524 1.524)
					(thickness 0.254)
				)
			)
		)
		(sheetname "ZED-F9T")
		(sheetfile "ZED-F9T.kicad_sch")
		(duplicate_pad_numbers_are_jumpers no)
		(fp_line
			(start -0.8 1.05)
			(end -0.8 -1.05)
			(stroke
				(width 0.2)
				(type solid)
			)
			(layer "F.SilkS")
		)
		(fp_line
			(start 0.8 1.05)
			(end -0.8 1.05)
			(stroke
				(width 0.2)
				(type solid)
			)
			(layer "F.SilkS")
		)
		(fp_line
			(start 0.8 1.05)
			(end 0.8 -1.05)
			(stroke
				(width 0.2)
				(type solid)
			)
			(layer "F.SilkS")
		)
		(fp_line
			(start 0.8 -1.05)
			(end -0.8 -1.05)
			(stroke
				(width 0.2)
				(type solid)
			)
			(layer "F.SilkS")
		)
		(fp_circle
			(center -1.6 -1.45)
			(end -1.725 -1.45)
			(stroke
				(width 0.25)
				(type solid)
			)
			(fill no)
			(layer "F.SilkS")
		)
		(fp_line
			(start -2.225 1.3)
			(end -2.225 -1.3)
			(stroke
				(width 0.05)
				(type solid)
			)
			(layer "F.CrtYd")
		)
		(fp_line
			(start 2.225 1.3)
			(end -2.225 1.3)
			(stroke
				(width 0.05)
				(type solid)
			)
			(layer "F.CrtYd")
		)
		(fp_line
			(start 2.225 1.3)
			(end 2.225 -1.3)
			(stroke
				(width 0.05)
				(type solid)
			)
			(layer "F.CrtYd")
		)
		(fp_line
			(start 0 0.5)
			(end 0 -0.5)
			(stroke
				(width 0.1)
				(type solid)
			)
			(layer "F.CrtYd")
		)
		(fp_line
			(start 0.5 0)
			(end -0.5 0)
			(stroke
				(width 0.1)
				(type solid)
			)
			(layer "F.CrtYd")
		)
		(fp_line
			(start 2.225 -1.3)
			(end -2.225 -1.3)
			(stroke
				(width 0.05)
				(type solid)
			)
			(layer "F.CrtYd")
		)
		(pad "1" smd roundrect
			(at -1.6 -0.75)
			(size 0.3 0.8)
			(layers "F.Cu" "F.Mask" "F.Paste")
			(roundrect_rratio 0.165)
			(net "RXD_IN")
		)
		(pad "2" smd roundrect
			(at -1.6 -0.25)
			(size 0.3 0.8)
			(layers "F.Cu" "F.Mask" "F.Paste")
			(roundrect_rratio 0.165)
		)
		(pad "3" smd roundrect
			(at -1.6 0.25)
			(size 0.3 0.8)
			(layers "F.Cu" "F.Mask" "F.Paste")
			(roundrect_rratio 0.165)
			(net "TXD")
		)
		(pad "4" smd roundrect
			(at -1.6 0.75)
			(size 0.3 0.8)
			(layers "F.Cu" "F.Mask" "F.Paste")
			(roundrect_rratio 0.165)
			(net "GND")
		)
		(pad "5" smd roundrect
			(at 1.6 0.75)
			(size 0.3 0.8)
			(layers "F.Cu" "F.Mask" "F.Paste")
			(roundrect_rratio 0.165)
			(net "TXD_OUT")
		)
		(pad "6" smd roundrect
			(at 1.6 0.25)
			(size 0.3 0.8)
			(layers "F.Cu" "F.Mask" "F.Paste")
			(roundrect_rratio 0.165)
		)
		(pad "7" smd roundrect
			(at 1.6 -0.25)
			(size 0.3 0.8)
			(layers "F.Cu" "F.Mask" "F.Paste")
			(roundrect_rratio 0.165)
			(net "RXD")
		)
		(pad "8" smd roundrect
			(at 1.6 -0.75)
			(size 0.3 0.8)
			(layers "F.Cu" "F.Mask" "F.Paste")
			(roundrect_rratio 0.165)
			(net "VCC")
		)
	)
	(footprint "Vault:TP001V_SMT_100DIA"
		(layer "F.Cu")
		(at 157.8411 118.4631 90)
		(property "Reference" "TP7"
			(at 3.96 0.20607 90)
			(unlocked yes)
			(layer "F.SilkS")
			(effects
				(font
					(size 0.8 0.8)
					(thickness 0.15)
				)
			)
		)
		(property "Value" "SMT_100DIA"
			(at -2.124202 7.0716 0)
			(unlocked yes)
			(layer "F.SilkS")
			(hide yes)
			(effects
				(font
					(size 1.524 1.524)
					(thickness 0.254)
				)
			)
		)
		(sheetname "ZED-F9T")
		(sheetfile "ZED-F9T.kicad_sch")
		(duplicate_pad_numbers_are_jumpers no)
		(pad "1" smd circle
			(at 1.397 0 90)
			(size 1 1)
			(layers "F.Cu" "F.Mask" "F.Paste")
			(net "NetTP7_1")
			(solder_mask_margin 0.05)
			(solder_paste_margin 0)
			(thermal_bridge_angle 90)
		)
	)
	(footprint "Vault:FP-RMCF0402-IPC_C"
		(layer "F.Cu")
		(at 175.8497 101.11983 90)
		(property "Reference" "R4"
			(at 2.38506 -0.04793 90)
			(unlocked yes)
			(layer "F.SilkS")
			(effects
				(font
					(size 0.8 0.8)
					(thickness 0.14986)
				)
			)
		)
		(property "Value" "10k"
			(at -2.352802 1.434525 0)
			(unlocked yes)
			(layer "F.SilkS")
			(hide yes)
			(effects
				(font
					(size 1.524 1.524)
					(thickness 0.254)
				)
			)
		)
		(sheetname "ZED-F9T")
		(sheetfile "ZED-F9T.kicad_sch")
		(duplicate_pad_numbers_are_jumpers no)
		(fp_line
			(start -0.65607 -0.675)
			(end 0.65607 -0.675)
			(stroke
				(width 0.2)
				(type solid)
			)
			(layer "F.SilkS")
		)
		(fp_line
			(start -0.65607 0.675)
			(end 0.65607 0.675)
			(stroke
				(width 0.2)
				(type solid)
			)
			(layer "F.SilkS")
		)
		(fp_line
			(start 0.75606 -0.375)
			(end 0.75606 0.375)
			(stroke
				(width 0.2)
				(type solid)
			)
			(layer "F.CrtYd")
		)
		(fp_line
			(start -0.75607 -0.375)
			(end 0.75606 -0.375)
			(stroke
				(width 0.2)
				(type solid)
			)
			(layer "F.CrtYd")
		)
		(fp_line
			(start -0.75607 -0.375)
			(end -0.75607 0.375)
			(stroke
				(width 0.2)
				(type solid)
			)
			(layer "F.CrtYd")
		)
		(fp_line
			(start -0.75607 0.375)
			(end 0.75606 0.375)
			(stroke
				(width 0.2)
				(type solid)
			)
			(layer "F.CrtYd")
		)
		(fp_line
			(start 0 -0.5)
			(end 0 0.5)
			(stroke
				(width 0.1)
				(type solid)
			)
			(layer "F.Fab")
		)
		(fp_line
			(start 0.75606 -0.375)
			(end 0.75606 0.375)
			(stroke
				(width 0.2)
				(type solid)
			)
			(layer "F.Fab")
		)
		(fp_line
			(start -0.75607 -0.375)
			(end 0.75606 -0.375)
			(stroke
				(width 0.2)
				(type solid)
			)
			(layer "F.Fab")
		)
		(fp_line
			(start -0.75607 -0.375)
			(end -0.75607 0.375)
			(stroke
				(width 0.2)
				(type solid)
			)
			(layer "F.Fab")
		)
		(fp_line
			(start -0.5 0)
			(end 0.5 0)
			(stroke
				(width 0.1)
				(type solid)
			)
			(layer "F.Fab")
		)
		(fp_line
			(start -0.75607 0.375)
			(end 0.75606 0.375)
			(stroke
				(width 0.2)
				(type solid)
			)
			(layer "F.Fab")
		)
		(fp_text user "${REFERENCE}"
			(at -0.00002 0.10711 90)
			(unlocked yes)
			(layer "F.Fab")
			(effects
				(font
					(face "Arial")
					(size 0.63 0.63)
					(thickness 0.1)
				)
				(justify left bottom)
			)
		)
		(pad "1" smd rect
			(at -0.36554 0 90)
			(size 0.58106 0.47247)
			(layers "F.Cu" "F.Mask" "F.Paste")
			(net "GND")
			(solder_mask_margin 0)
			(solder_paste_margin 0)
		)
		(pad "2" smd rect
			(at 0.36553 0 90)
			(size 0.58106 0.47247)
			(layers "F.Cu" "F.Mask" "F.Paste")
			(net "NetDS1_K")
			(solder_mask_margin 0)
			(solder_paste_margin 0)
		)
	)
	(footprint "Vault:FP-PESD0402-MFG"
		(layer "F.Cu")
		(at 125.8371 101.9531 90)
		(property "Reference" "D1"
			(at 2.13073 0.15 0)
			(unlocked yes)
			(layer "F.SilkS")
			(effects
				(font
					(size 0.8 0.8)
					(thickness 0.15)
				)
			)
		)
		(property "Value" "PESD0402-140"
			(at -2.378202 8.010865 0)
			(unlocked yes)
			(layer "F.SilkS")
			(hide yes)
			(effects
				(font
					(size 1.524 1.524)
					(thickness 0.254)
				)
			)
		)
		(sheetname "Antenna_Supervisor")
		(sheetfile "Antenna_Supervisor.kicad_sch")
		(duplicate_pad_numbers_are_jumpers no)
		(fp_line
			(start -0.55 -0.7)
			(end 0.55 -0.7)
			(stroke
				(width 0.2)
				(type solid)
			)
			(layer "F.SilkS")
		)
		(fp_line
			(start -0.56 0.69)
			(end 0.54 0.69)
			(stroke
				(width 0.2)
				(type solid)
			)
			(layer "F.SilkS")
		)
		(fp_line
			(start 1.15 -0.425)
			(end 1.15 0.425)
			(stroke
				(width 0.2)
				(type solid)
			)
			(layer "F.CrtYd")
		)
		(fp_line
			(start -1.15 -0.425)
			(end 1.15 -0.425)
			(stroke
				(width 0.2)
				(type solid)
			)
			(layer "F.CrtYd")
		)
		(fp_line
			(start -1.15 -0.425)
			(end -1.15 0.425)
			(stroke
				(width 0.2)
				(type solid)
			)
			(layer "F.CrtYd")
		)
		(fp_line
			(start -1.15 0.425)
			(end 1.15 0.425)
			(stroke
				(width 0.2)
				(type solid)
			)
			(layer "F.CrtYd")
		)
		(fp_line
			(start 0 -0.5)
			(end 0 0.5)
			(stroke
				(width 0.1)
				(type solid)
			)
			(layer "F.Fab")
		)
		(fp_line
			(start 1.15 -0.425)
			(end 1.15 0.425)
			(stroke
				(width 0.2)
				(type solid)
			)
			(layer "F.Fab")
		)
		(fp_line
			(start -1.15 -0.425)
			(end 1.15 -0.425)
			(stroke
				(width 0.2)
				(type solid)
			)
			(layer "F.Fab")
		)
		(fp_line
			(start -1.15 -0.425)
			(end -1.15 0.425)
			(stroke
				(width 0.2)
				(type solid)
			)
			(layer "F.Fab")
		)
		(fp_line
			(start -0.5 0)
			(end 0.5 0)
			(stroke
				(width 0.1)
				(type solid)
			)
			(layer "F.Fab")
		)
		(fp_line
			(start -1.15 0.425)
			(end 1.15 0.425)
			(stroke
				(width 0.2)
				(type solid)
			)
			(layer "F.Fab")
		)
		(fp_text user "${REFERENCE}"
			(at -0.1524 -1.0105 90)
			(unlocked yes)
			(layer "F.Fab")
			(effects
				(font
					(face "Arial")
					(size 0.63 0.63)
					(thickness 0.1)
				)
				(justify left bottom)
			)
		)
		(pad "1" smd rect
			(at -0.625 0 90)
			(size 0.85 0.65)
			(layers "F.Cu" "F.Mask" "F.Paste")
			(net "GND")
			(solder_mask_margin 0)
			(solder_paste_margin 0)
		)
		(pad "2" smd rect
			(at 0.625 0 90)
			(size 0.85 0.65)
			(layers "F.Cu" "F.Mask" "F.Paste")
			(net "RF_ANT")
			(solder_mask_margin 0)
			(solder_paste_margin 0)
		)
	)
	(footprint "Vault:CAPC1005X055N"
		(layer "F.Cu")
		(at 147.3001 94.8411 90)
		(property "Reference" "C5"
			(at 2.182 0.02827 90)
			(unlocked yes)
			(layer "F.SilkS")
			(effects
				(font
					(size 0.8 0.8)
					(thickness 0.15)
				)
			)
		)
		(property "Value" "Murata_GRM155R61E105KA12D"
			(at -2.584202 17.199825 0)
			(unlocked yes)
			(layer "F.SilkS")
			(hide yes)
			(effects
				(font
					(size 1.524 1.524)
					(thickness 0.254)
				)
			)
		)
		(sheetname "ZED-F9T")
		(sheetfile "ZED-F9T.kicad_sch")
		(duplicate_pad_numbers_are_jumpers no)
		(fp_line
			(start 0.95 -0.5)
			(end 0.95 0.5)
			(stroke
				(width 0.1)
				(type solid)
			)
			(layer "F.CrtYd")
		)
		(fp_line
			(start -0.95 -0.5)
			(end 0.95 -0.5)
			(stroke
				(width 0.1)
				(type solid)
			)
			(layer "F.CrtYd")
		)
		(fp_line
			(start -0.95 -0.5)
			(end -0.95 0.5)
			(stroke
				(width 0.1)
				(type solid)
			)
			(layer "F.CrtYd")
		)
		(fp_line
			(start -0.95 0.5)
			(end 0.95 0.5)
			(stroke
				(width 0.1)
				(type solid)
			)
			(layer "F.CrtYd")
		)
		(fp_line
			(start 0.5 -0.25)
			(end 0.5 0.25)
			(stroke
				(width 0.05)
				(type solid)
			)
			(layer "F.Fab")
		)
		(fp_line
			(start -0.5 -0.25)
			(end 0.5 -0.25)
			(stroke
				(width 0.05)
				(type solid)
			)
			(layer "F.Fab")
		)
		(fp_line
			(start -0.5 -0.25)
			(end -0.5 0.25)
			(stroke
				(width 0.05)
				(type solid)
			)
			(layer "F.Fab")
		)
		(fp_line
			(start -0.5 0.25)
			(end 0.5 0.25)
			(stroke
				(width 0.05)
				(type solid)
			)
			(layer "F.Fab")
		)
		(fp_text_box "${REFERENCE}"
			(start -1.09004 -0.20727)
			(end 1.09004 0.20726)
			(margins 0 0 0 0)
			(layer "F.Fab")
			(effects
				(font
					(face "Arial")
					(size 0.315 0.315)
					(thickness 0.254)
				)
				(justify top)
			)
			(border no)
			(stroke
				(width 0.1)
				(type default)
			)
			(knockout no)
		)
		(pad "1" smd rect
			(at -0.46 0 90)
			(size 0.6 0.62)
			(layers "F.Cu" "F.Mask" "F.Paste")
			(net "NetC5_1")
			(solder_mask_margin 0.05)
			(solder_paste_margin 0)
		)
		(pad "2" smd rect
			(at 0.46 0 90)
			(size 0.6 0.62)
			(layers "F.Cu" "F.Mask" "F.Paste")
			(net "GND")
			(solder_mask_margin 0.05)
			(solder_paste_margin 0)
		)
	)
	(footprint "Vault:FP-GRM033-0_03-IPC_B"
		(layer "F.Cu")
		(at 127.6151 104.3661 180)
		(property "Reference" "C10"
			(at 1.678805 -0.00287 0)
			(unlocked yes)
			(layer "F.SilkS")
			(effects
				(font
					(size 0.8 0.8)
					(thickness 0.15)
				)
			)
		)
		(property "Value" "10nF"
			(at -2.39944 -2.251202 0)
			(unlocked yes)
			(layer "F.SilkS")
			(hide yes)
			(effects
				(font
					(size 1.524 1.524)
					(thickness 0.254)
				)
			)
		)
		(sheetname "Antenna_Supervisor")
		(sheetfile "Antenna_Supervisor.kicad_sch")
		(duplicate_pad_numbers_are_jumpers no)
		(fp_line
			(start 0.53137 0.58137)
			(end -0.53137 0.58137)
			(stroke
				(width 0.2)
				(type solid)
			)
			(layer "F.SilkS")
		)
		(fp_line
			(start 0.53137 -0.58137)
			(end -0.53137 -0.58137)
			(stroke
				(width 0.2)
				(type solid)
			)
			(layer "F.SilkS")
		)
		(fp_line
			(start 0.68137 0.33137)
			(end -0.68137 0.33137)
			(stroke
				(width 0.2)
				(type solid)
			)
			(layer "F.CrtYd")
		)
		(fp_line
			(start 0.68137 -0.33137)
			(end 0.68137 0.33137)
			(stroke
				(width 0.2)
				(type solid)
			)
			(layer "F.CrtYd")
		)
		(fp_line
			(start 0.68137 -0.33137)
			(end -0.68137 -0.33137)
			(stroke
				(width 0.2)
				(type solid)
			)
			(layer "F.CrtYd")
		)
		(fp_line
			(start -0.68137 -0.33137)
			(end -0.68137 0.33137)
			(stroke
				(width 0.2)
				(type solid)
			)
			(layer "F.CrtYd")
		)
		(fp_line
			(start 0.68137 0.33137)
			(end -0.68137 0.33137)
			(stroke
				(width 0.2)
				(type solid)
			)
			(layer "F.Fab")
		)
		(fp_line
			(start 0.68137 -0.33137)
			(end 0.68137 0.33137)
			(stroke
				(width 0.2)
				(type solid)
			)
			(layer "F.Fab")
		)
		(fp_line
			(start 0.68137 -0.33137)
			(end -0.68137 -0.33137)
			(stroke
				(width 0.2)
				(type solid)
			)
			(layer "F.Fab")
		)
		(fp_line
			(start 0.5 0)
			(end -0.5 0)
			(stroke
				(width 0.1)
				(type solid)
			)
			(layer "F.Fab")
		)
		(fp_line
			(start 0 -0.5)
			(end 0 0.5)
			(stroke
				(width 0.1)
				(type solid)
			)
			(layer "F.Fab")
		)
		(fp_line
			(start -0.68137 -0.33137)
			(end -0.68137 0.33137)
			(stroke
				(width 0.2)
				(type solid)
			)
			(layer "F.Fab")
		)
		(fp_text user "${REFERENCE}"
			(at 0.7366 -1.64587 360)
			(unlocked yes)
			(layer "F.Fab")
			(effects
				(font
					(face "Arial")
					(size 0.63 0.63)
					(thickness 0.1)
				)
				(justify left bottom)
			)
		)
		(pad "1" smd rect
			(at -0.30431 0 180)
			(size 0.45411 0.36274)
			(layers "F.Cu" "F.Mask" "F.Paste")
			(net "NetC10_1")
			(solder_mask_margin 0)
			(solder_paste_margin 0)
		)
		(pad "2" smd rect
			(at 0.30431 0 180)
			(size 0.45411 0.36274)
			(layers "F.Cu" "F.Mask" "F.Paste")
			(net "GND")
			(solder_mask_margin 0)
			(solder_paste_margin 0)
		)
	)
	(footprint "Vault:FP-0402-L_1_0_0_05-W_0_5-IPC_B"
		(layer "F.Cu")
		(at 168.808 109.8525)
		(property "Reference" "C6"
			(at 0.1305 1.52687 360)
			(unlocked yes)
			(layer "F.SilkS")
			(effects
				(font
					(size 0.8 0.8)
					(thickness 0.15)
				)
			)
		)
		(property "Value" "100nF"
			(at 2.95799 2.352802 0)
			(unlocked yes)
			(layer "F.SilkS")
			(hide yes)
			(effects
				(font
					(size 1.524 1.524)
					(thickness 0.254)
				)
			)
		)
		(sheetname "ZED-F9T")
		(sheetfile "ZED-F9T.kicad_sch")
		(duplicate_pad_numbers_are_jumpers no)
		(fp_line
			(start -0.73624 -0.68624)
			(end 0.73623 -0.68624)
			(stroke
				(width 0.2)
				(type solid)
			)
			(layer "F.SilkS")
		)
		(fp_line
			(start -0.73624 0.68624)
			(end 0.73623 0.68624)
			(stroke
				(width 0.2)
				(type solid)
			)
			(layer "F.SilkS")
		)
		(fp_line
			(start -0.88624 -0.43624)
			(end 0.88623 -0.43624)
			(stroke
				(width 0.2)
				(type solid)
			)
			(layer "F.CrtYd")
		)
		(fp_line
			(start -0.88624 0.43624)
			(end -0.88624 -0.43624)
			(stroke
				(width 0.2)
				(type solid)
			)
			(layer "F.CrtYd")
		)
		(fp_line
			(start -0.88624 0.43624)
			(end 0.88623 0.43624)
			(stroke
				(width 0.2)
				(type solid)
			)
			(layer "F.CrtYd")
		)
		(fp_line
			(start 0.88623 0.43624)
			(end 0.88623 -0.43624)
			(stroke
				(width 0.2)
				(type solid)
			)
			(layer "F.CrtYd")
		)
		(fp_line
			(start -0.88624 -0.43624)
			(end 0.88623 -0.43624)
			(stroke
				(width 0.2)
				(type solid)
			)
			(layer "F.Fab")
		)
		(fp_line
			(start -0.88624 0.43624)
			(end -0.88624 -0.43624)
			(stroke
				(width 0.2)
				(type solid)
			)
			(layer "F.Fab")
		)
		(fp_line
			(start -0.88624 0.43624)
			(end 0.88623 0.43624)
			(stroke
				(width 0.2)
				(type solid)
			)
			(layer "F.Fab")
		)
		(fp_line
			(start -0.5 0)
			(end 0.5 0)
			(stroke
				(width 0.1)
				(type solid)
			)
			(layer "F.Fab")
		)
		(fp_line
			(start 0 0.5)
			(end 0 -0.5)
			(stroke
				(width 0.1)
				(type solid)
			)
			(layer "F.Fab")
		)
		(fp_line
			(start 0.88623 0.43624)
			(end 0.88623 -0.43624)
			(stroke
				(width 0.2)
				(type solid)
			)
			(layer "F.Fab")
		)
		(fp_text user "${REFERENCE}"
			(at -0.00002 0.09648 360)
			(unlocked yes)
			(layer "F.Fab")
			(effects
				(font
					(face "Arial")
					(size 0.63 0.63)
					(thickness 0.1)
				)
				(justify left bottom)
			)
		)
		(pad "1" smd rect
			(at -0.42856 0)
			(size 0.61535 0.57247)
			(layers "F.Cu" "F.Mask" "F.Paste")
			(net "VCC")
			(solder_mask_margin 0)
			(solder_paste_margin 0)
		)
		(pad "2" smd rect
			(at 0.42856 0)
			(size 0.61535 0.57247)
			(layers "F.Cu" "F.Mask" "F.Paste")
			(net "GND")
			(solder_mask_margin 0)
			(solder_paste_margin 0)
		)
	)
	(footprint "Vault:LEDS160X80X110-2N_LXFM0603-GR"
		(layer "F.Cu")
		(at 178.1865 100.2259 -90)
		(property "Reference" "DS1"
			(at -3.29946 -0.00287 90)
			(unlocked yes)
			(layer "F.SilkS")
			(effects
				(font
					(size 0.8 0.8)
					(thickness 0.14986)
				)
			)
		)
		(property "Value" "Lumex_SML-LXFM0603SUGCTR"
			(at 3.318002 -17.78687 0)
			(unlocked yes)
			(layer "F.SilkS")
			(hide yes)
			(effects
				(font
					(size 1.524 1.524)
					(thickness 0.254)
				)
			)
		)
		(sheetname "ZED-F9T")
		(sheetfile "ZED-F9T.kicad_sch")
		(duplicate_pad_numbers_are_jumpers no)
		(fp_line
			(start -1.6 0.3)
			(end -1.6 -0.3)
			(stroke
				(width 0.1)
				(type solid)
			)
			(layer "F.SilkS")
		)
		(fp_line
			(start -1.7 0.7)
			(end -1.7 -0.7)
			(stroke
				(width 0.1)
				(type solid)
			)
			(layer "F.CrtYd")
		)
		(fp_line
			(start 1.7 0.7)
			(end -1.7 0.7)
			(stroke
				(width 0.1)
				(type solid)
			)
			(layer "F.CrtYd")
		)
		(fp_line
			(start 1.7 0.7)
			(end 1.7 -0.7)
			(stroke
				(width 0.1)
				(type solid)
			)
			(layer "F.CrtYd")
		)
		(fp_line
			(start 1.7 -0.7)
			(end -1.7 -0.7)
			(stroke
				(width 0.1)
				(type solid)
			)
			(layer "F.CrtYd")
		)
		(fp_line
			(start -0.79991 0.39983)
			(end -0.79991 -0.40013)
			(stroke
				(width 0.05)
				(type solid)
			)
			(layer "F.Fab")
		)
		(fp_line
			(start 0.80017 0.39983)
			(end -0.79991 0.39983)
			(stroke
				(width 0.05)
				(type solid)
			)
			(layer "F.Fab")
		)
		(fp_line
			(start 0.80017 0.39983)
			(end 0.80017 -0.40013)
			(stroke
				(width 0.05)
				(type solid)
			)
			(layer "F.Fab")
		)
		(fp_line
			(start -0.1 0.3)
			(end -0.1 -0.3)
			(stroke
				(width 0.05)
				(type solid)
			)
			(layer "F.Fab")
		)
		(fp_line
			(start 0.1 0.2)
			(end -0.1 0)
			(stroke
				(width 0.05)
				(type solid)
			)
			(layer "F.Fab")
		)
		(fp_line
			(start 0.1 0.2)
			(end 0.1 -0.2)
			(stroke
				(width 0.05)
				(type solid)
			)
			(layer "F.Fab")
		)
		(fp_line
			(start -0.1 0)
			(end 0.1 -0.2)
			(stroke
				(width 0.05)
				(type solid)
			)
			(layer "F.Fab")
		)
		(fp_line
			(start 0.80017 -0.40013)
			(end -0.79991 -0.40013)
			(stroke
				(width 0.05)
				(type solid)
			)
			(layer "F.Fab")
		)
		(fp_text_box "${REFERENCE}"
			(start -2.76472 -0.52514)
			(end 2.76472 0.52513)
			(margins 0 0 0 0)
			(layer "F.Fab")
			(effects
				(font
					(face "Arial")
					(size 0.8001 0.8001)
					(thickness 0.254)
				)
				(justify top)
			)
			(border no)
			(stroke
				(width 0.1)
				(type default)
			)
			(knockout no)
		)
		(pad "A" smd rect
			(at 0.825 0 270)
			(size 0.8 0.8)
			(layers "F.Cu" "F.Mask" "F.Paste")
			(net "TP2")
			(solder_mask_margin 0.05)
			(solder_paste_margin 0)
		)
		(pad "K" smd rect
			(at -0.825 0 270)
			(size 0.8 0.8)
			(layers "F.Cu" "F.Mask" "F.Paste")
			(net "NetDS1_K")
			(solder_mask_margin 0.05)
			(solder_paste_margin 0)
		)
	)
	(footprint "GNSS_Receiver_Library:GPS_ZED-F9T"
		(locked yes)
		(layer "F.Cu")
		(at 139.25811 100.0441 -90)
		(property "Reference" "U1"
			(at -3.39673 1.58701 0)
			(unlocked yes)
			(layer "F.SilkS")
			(effects
				(font
					(size 0.8 0.8)
					(thickness 0.15)
				)
			)
		)
		(property "Value" "ZED-F9T-00B"
			(at 17.651602 -5.494845 0)
			(unlocked yes)
			(layer "F.SilkS")
			(hide yes)
			(effects
				(font
					(size 1.524 1.524)
					(thickness 0.254)
				)
			)
		)
		(sheetname "ZED-F9T")
		(sheetfile "ZED-F9T.kicad_sch")
		(duplicate_pad_numbers_are_jumpers no)
		(fp_circle
			(center 0.05 2.4)
			(end -0.0262 2.4)
			(stroke
				(width 0.762)
				(type solid)
			)
			(fill no)
			(layer "F.SilkS")
		)
		(pad "1" smd rect
			(at 0 0 270)
			(size 0.8 1.5)
			(layers "F.Cu" "F.Mask" "F.Paste")
			(net "GND")
		)
		(pad "2" smd rect
			(at 1.1 0 270)
			(size 0.8 1.5)
			(layers "F.Cu" "F.Mask" "F.Paste")
			(net "RF_IN")
		)
		(pad "3" smd rect
			(at 2.2 0 270)
			(size 0.8 1.5)
			(layers "F.Cu" "F.Mask" "F.Paste")
			(net "GND")
		)
		(pad "4" smd rect
			(at 3.3 0 270)
			(size 0.8 1.5)
			(layers "F.Cu" "F.Mask" "F.Paste")
			(net "ANT_DET")
		)
		(pad "5" smd rect
			(at 4.4 0 270)
			(size 0.8 1.5)
			(layers "F.Cu" "F.Mask" "F.Paste")
			(net "ANT_OFF")
		)
		(pad "6" smd rect
			(at 5.5 0 270)
			(size 0.8 1.5)
			(layers "F.Cu" "F.Mask" "F.Paste")
			(net "ANT_SHORT_N")
		)
		(pad "7" smd rect
			(at 6.6 0 270)
			(size 0.8 1.5)
			(layers "F.Cu" "F.Mask" "F.Paste")
		)
		(pad "8" smd rect
			(at 7.7 0 270)
			(size 0.8 1.5)
			(layers "F.Cu" "F.Mask" "F.Paste")
		)
		(pad "9" smd rect
			(at 8.8 0 270)
			(size 0.8 1.5)
			(layers "F.Cu" "F.Mask" "F.Paste")
		)
		(pad "10" smd rect
			(at 9.9 0 270)
			(size 0.8 1.5)
			(layers "F.Cu" "F.Mask" "F.Paste")
		)
		(pad "11" smd rect
			(at 11 0 270)
			(size 0.8 1.5)
			(layers "F.Cu" "F.Mask" "F.Paste")
		)
		(pad "12" smd rect
			(at 12.1 0 270)
			(size 0.8 1.5)
			(layers "F.Cu" "F.Mask" "F.Paste")
			(net "GND")
		)
		(pad "13" smd rect
			(at 13.2 0 270)
			(size 0.8 1.5)
			(layers "F.Cu" "F.Mask" "F.Paste")
		)
		(pad "14" smd rect
			(at 14.3 0 270)
			(size 0.8 1.5)
			(layers "F.Cu" "F.Mask" "F.Paste")
			(net "GND")
		)
		(pad "15" smd rect
			(at 17.1 -0.85)
			(size 0.8 1.5)
			(layers "F.Cu" "F.Mask" "F.Paste")
		)
		(pad "16" smd rect
			(at 17.1 -1.95)
			(size 0.8 1.5)
			(layers "F.Cu" "F.Mask" "F.Paste")
		)
		(pad "17" smd rect
			(at 17.1 -3.05)
			(size 0.8 1.5)
			(layers "F.Cu" "F.Mask" "F.Paste")
		)
		(pad "18" smd rect
			(at 17.1 -4.15)
			(size 0.8 1.5)
			(layers "F.Cu" "F.Mask" "F.Paste")
		)
		(pad "19" smd rect
			(at 17.1 -5.25)
			(size 0.8 1.5)
			(layers "F.Cu" "F.Mask" "F.Paste")
			(net "NetTP8_1")
		)
		(pad "20" smd rect
			(at 17.1 -6.35)
			(size 0.8 1.5)
			(layers "F.Cu" "F.Mask" "F.Paste")
		)
		(pad "21" smd rect
			(at 17.1 -7.45)
			(size 0.8 1.5)
			(layers "F.Cu" "F.Mask" "F.Paste")
		)
		(pad "22" smd rect
			(at 17.1 -8.55)
			(size 0.8 1.5)
			(layers "F.Cu" "F.Mask" "F.Paste")
		)
		(pad "23" smd rect
			(at 17.1 -9.65)
			(size 0.8 1.5)
			(layers "F.Cu" "F.Mask" "F.Paste")
		)
		(pad "24" smd rect
			(at 17.1 -10.75)
			(size 0.8 1.5)
			(layers "F.Cu" "F.Mask" "F.Paste")
		)
		(pad "25" smd rect
			(at 17.1 -11.85)
			(size 0.8 1.5)
			(layers "F.Cu" "F.Mask" "F.Paste")
		)
		(pad "26" smd rect
			(at 17.1 -12.95)
			(size 0.8 1.5)
			(layers "F.Cu" "F.Mask" "F.Paste")
			(net "NetTP7_1")
		)
		(pad "27" smd rect
			(at 17.1 -14.05)
			(size 0.8 1.5)
			(layers "F.Cu" "F.Mask" "F.Paste")
			(net "NetTP6_1")
		)
		(pad "28" smd rect
			(at 14.3 -14.9 270)
			(size 0.8 1.5)
			(layers "F.Cu" "F.Mask" "F.Paste")
		)
		(pad "29" smd rect
			(at 13.2 -14.9 270)
			(size 0.8 1.5)
			(layers "F.Cu" "F.Mask" "F.Paste")
		)
		(pad "30" smd rect
			(at 12.1 -14.9 270)
			(size 0.8 1.5)
			(layers "F.Cu" "F.Mask" "F.Paste")
		)
		(pad "31" smd rect
			(at 11 -14.9 270)
			(size 0.8 1.5)
			(layers "F.Cu" "F.Mask" "F.Paste")
		)
		(pad "32" smd rect
			(at 9.9 -14.9 270)
			(size 0.8 1.5)
			(layers "F.Cu" "F.Mask" "F.Paste")
			(net "GND")
		)
		(pad "33" smd rect
			(at 8.8 -14.9 270)
			(size 0.8 1.5)
			(layers "F.Cu" "F.Mask" "F.Paste")
			(net "VCC")
		)
		(pad "34" smd rect
			(at 7.7 -14.9 270)
			(size 0.8 1.5)
			(layers "F.Cu" "F.Mask" "F.Paste")
			(net "VCC")
		)
		(pad "35" smd rect
			(at 6.6 -14.9 270)
			(size 0.8 1.5)
			(layers "F.Cu" "F.Mask" "F.Paste")
		)
		(pad "36" smd rect
			(at 5.5 -14.9 270)
			(size 0.8 1.5)
			(layers "F.Cu" "F.Mask" "F.Paste")
			(net "VCC")
		)
		(pad "37" smd rect
			(at 4.4 -14.9 270)
			(size 0.8 1.5)
			(layers "F.Cu" "F.Mask" "F.Paste")
			(net "GND")
		)
		(pad "38" smd rect
			(at 3.3 -14.9 270)
			(size 0.8 1.5)
			(layers "F.Cu" "F.Mask" "F.Paste")
			(net "GND")
		)
		(pad "39" smd rect
			(at 2.2 -14.9 270)
			(size 0.8 1.5)
			(layers "F.Cu" "F.Mask" "F.Paste")
		)
		(pad "40" smd rect
			(at 1.1 -14.9 270)
			(size 0.8 1.5)
			(layers "F.Cu" "F.Mask" "F.Paste")
		)
		(pad "41" smd rect
			(at 0 -14.9 270)
			(size 0.8 1.5)
			(layers "F.Cu" "F.Mask" "F.Paste")
			(net "GND")
		)
		(pad "42" smd rect
			(at -2.8 -14.05)
			(size 0.8 1.5)
			(layers "F.Cu" "F.Mask" "F.Paste")
			(net "TXD")
		)
		(pad "43" smd rect
			(at -2.8 -12.95)
			(size 0.8 1.5)
			(layers "F.Cu" "F.Mask" "F.Paste")
			(net "RXD")
		)
		(pad "44" smd rect
			(at -2.8 -11.85)
			(size 0.8 1.5)
			(layers "F.Cu" "F.Mask" "F.Paste")
			(net "NetTP4_1")
		)
		(pad "45" smd rect
			(at -2.8 -10.75)
			(size 0.8 1.5)
			(layers "F.Cu" "F.Mask" "F.Paste")
			(net "NetTP5_1")
		)
		(pad "46" smd rect
			(at -2.8 -9.65)
			(size 0.8 1.5)
			(layers "F.Cu" "F.Mask" "F.Paste")
		)
		(pad "47" smd rect
			(at -2.8 -8.55)
			(size 0.8 1.5)
			(layers "F.Cu" "F.Mask" "F.Paste")
			(net "NetC5_1")
		)
		(pad "48" smd rect
			(at -2.8 -7.45)
			(size 0.8 1.5)
			(layers "F.Cu" "F.Mask" "F.Paste")
			(net "GND")
		)
		(pad "49" smd rect
			(at -2.8 -6.35)
			(size 0.8 1.5)
			(layers "F.Cu" "F.Mask" "F.Paste")
			(net "RST")
		)
		(pad "50" smd rect
			(at -2.8 -5.25)
			(size 0.8 1.5)
			(layers "F.Cu" "F.Mask" "F.Paste")
			(net "NetTP1_1")
		)
		(pad "51" smd rect
			(at -2.8 -4.15)
			(size 0.8 1.5)
			(layers "F.Cu" "F.Mask" "F.Paste")
			(net "NetTP2_1")
		)
		(pad "52" smd rect
			(at -2.8 -3.05)
			(size 0.8 1.5)
			(layers "F.Cu" "F.Mask" "F.Paste")
			(net "NetTP3_1")
		)
		(pad "53" smd rect
			(at -2.8 -1.95)
			(size 0.8 1.5)
			(layers "F.Cu" "F.Mask" "F.Paste")
			(net "TP1")
		)
		(pad "54" smd rect
			(at -2.8 -0.85)
			(size 0.8 1.5)
			(layers "F.Cu" "F.Mask" "F.Paste")
			(net "TP2")
		)
		(pad "55" smd rect
			(at -0.2 -12.69998 270)
			(size 1.1 1.1)
			(layers "F.Cu" "F.Mask" "F.Paste")
			(net "GND")
		)
		(pad "55" smd rect
			(at -0.2 -10.59998 270)
			(size 1.1 1.1)
			(layers "F.Cu" "F.Mask" "F.Paste")
			(net "GND")
		)
		(pad "55" smd rect
			(at -0.2 -8.49998 270)
			(size 1.1 1.1)
			(layers "F.Cu" "F.Mask" "F.Paste")
			(net "GND")
		)
		(pad "55" smd rect
			(at -0.2 -6.39999 270)
			(size 1.1 1.1)
			(layers "F.Cu" "F.Mask" "F.Paste")
			(net "GND")
		)
		(pad "55" smd rect
			(at -0.2 -4.29999 270)
			(size 1.1 1.1)
			(layers "F.Cu" "F.Mask" "F.Paste")
			(net "GND")
		)
		(pad "55" smd rect
			(at -0.2 -2.2 270)
			(size 1.1 1.1)
			(layers "F.Cu" "F.Mask" "F.Paste")
			(net "GND")
		)
		(pad "55" smd rect
			(at 1.9 -12.69997 270)
			(size 1.1 1.1)
			(layers "F.Cu" "F.Mask" "F.Paste")
			(net "GND")
		)
		(pad "55" smd rect
			(at 1.9 -10.59998 270)
			(size 1.1 1.1)
			(layers "F.Cu" "F.Mask" "F.Paste")
			(net "GND")
		)
		(pad "55" smd rect
			(at 1.9 -8.49998 270)
			(size 1.1 1.1)
			(layers "F.Cu" "F.Mask" "F.Paste")
			(net "GND")
		)
		(pad "55" smd rect
			(at 1.9 -6.39998 270)
			(size 1.1 1.1)
			(layers "F.Cu" "F.Mask" "F.Paste")
			(net "GND")
		)
		(pad "55" smd rect
			(at 1.9 -4.29999 270)
			(size 1.1 1.1)
			(layers "F.Cu" "F.Mask" "F.Paste")
			(net "GND")
		)
		(pad "55" smd rect
			(at 1.9 -2.19999 270)
			(size 1.1 1.1)
			(layers "F.Cu" "F.Mask" "F.Paste")
			(net "GND")
		)
		(pad "55" smd rect
			(at 4 -12.69997 270)
			(size 1.1 1.1)
			(layers "F.Cu" "F.Mask" "F.Paste")
			(net "GND")
		)
		(pad "55" smd rect
			(at 4 -10.59998 270)
			(size 1.1 1.1)
			(layers "F.Cu" "F.Mask" "F.Paste")
			(net "GND")
		)
		(pad "55" smd rect
			(at 4 -8.49998 270)
			(size 1.1 1.1)
			(layers "F.Cu" "F.Mask" "F.Paste")
			(net "GND")
		)
		(pad "55" smd rect
			(at 4 -6.39998 270)
			(size 1.1 1.1)
			(layers "F.Cu" "F.Mask" "F.Paste")
			(net "GND")
		)
		(pad "55" smd rect
			(at 4 -4.29999 270)
			(size 1.1 1.1)
			(layers "F.Cu" "F.Mask" "F.Paste")
			(net "GND")
		)
		(pad "55" smd rect
			(at 4 -2.19999 270)
			(size 1.1 1.1)
			(layers "F.Cu" "F.Mask" "F.Paste")
			(net "GND")
		)
		(pad "55" smd rect
			(at 6.1 -12.69997 270)
			(size 1.1 1.1)
			(layers "F.Cu" "F.Mask" "F.Paste")
			(net "GND")
		)
		(pad "55" smd rect
			(at 6.1 -10.59998 270)
			(size 1.1 1.1)
			(layers "F.Cu" "F.Mask" "F.Paste")
			(net "GND")
		)
		(pad "55" smd rect
			(at 6.1 -8.49998 270)
			(size 1.1 1.1)
			(layers "F.Cu" "F.Mask" "F.Paste")
			(net "GND")
		)
		(pad "55" smd rect
			(at 6.1 -6.39998 270)
			(size 1.1 1.1)
			(layers "F.Cu" "F.Mask" "F.Paste")
			(net "GND")
		)
		(pad "55" smd rect
			(at 6.1 -4.29999 270)
			(size 1.1 1.1)
			(layers "F.Cu" "F.Mask" "F.Paste")
			(net "GND")
		)
		(pad "55" smd rect
			(at 6.1 -2.19999 270)
			(size 1.1 1.1)
			(layers "F.Cu" "F.Mask" "F.Paste")
			(net "GND")
		)
		(pad "55" smd rect
			(at 8.2 -12.69997 270)
			(size 1.1 1.1)
			(layers "F.Cu" "F.Mask" "F.Paste")
			(net "GND")
		)
		(pad "55" smd rect
			(at 8.2 -10.59998 270)
			(size 1.1 1.1)
			(layers "F.Cu" "F.Mask" "F.Paste")
			(net "GND")
		)
		(pad "55" smd rect
			(at 8.2 -8.49998 270)
			(size 1.1 1.1)
			(layers "F.Cu" "F.Mask" "F.Paste")
			(net "GND")
		)
		(pad "55" smd rect
			(at 8.2 -6.39998 270)
			(size 1.1 1.1)
			(layers "F.Cu" "F.Mask" "F.Paste")
			(net "GND")
		)
		(pad "55" smd rect
			(at 8.2 -4.29999 270)
			(size 1.1 1.1)
			(layers "F.Cu" "F.Mask" "F.Paste")
			(net "GND")
		)
		(pad "55" smd rect
			(at 8.2 -2.19999 270)
			(size 1.1 1.1)
			(layers "F.Cu" "F.Mask" "F.Paste")
			(net "GND")
		)
		(pad "55" smd rect
			(at 10.3 -12.69997 270)
			(size 1.1 1.1)
			(layers "F.Cu" "F.Mask" "F.Paste")
			(net "GND")
		)
		(pad "55" smd rect
			(at 10.3 -10.59998 270)
			(size 1.1 1.1)
			(layers "F.Cu" "F.Mask" "F.Paste")
			(net "GND")
		)
		(pad "55" smd rect
			(at 10.3 -8.49998 270)
			(size 1.1 1.1)
			(layers "F.Cu" "F.Mask" "F.Paste")
			(net "GND")
		)
		(pad "55" smd rect
			(at 10.3 -6.39998 270)
			(size 1.1 1.1)
			(layers "F.Cu" "F.Mask" "F.Paste")
			(net "GND")
		)
		(pad "55" smd rect
			(at 10.3 -4.29999 270)
			(size 1.1 1.1)
			(layers "F.Cu" "F.Mask" "F.Paste")
			(net "GND")
		)
		(pad "55" smd rect
			(at 10.3 -2.19999 270)
			(size 1.1 1.1)
			(layers "F.Cu" "F.Mask" "F.Paste")
			(net "GND")
		)
		(pad "55" smd rect
			(at 12.4 -12.69997 270)
			(size 1.1 1.1)
			(layers "F.Cu" "F.Mask" "F.Paste")
			(net "GND")
		)
		(pad "55" smd rect
			(at 12.4 -10.59998 270)
			(size 1.1 1.1)
			(layers "F.Cu" "F.Mask" "F.Paste")
			(net "GND")
		)
		(pad "55" smd rect
			(at 12.4 -8.49998 270)
			(size 1.1 1.1)
			(layers "F.Cu" "F.Mask" "F.Paste")
			(net "GND")
		)
		(pad "55" smd rect
			(at 12.4 -6.39998 270)
			(size 1.1 1.1)
			(layers "F.Cu" "F.Mask" "F.Paste")
			(net "GND")
		)
		(pad "55" smd rect
			(at 12.4 -4.29999 270)
			(size 1.1 1.1)
			(layers "F.Cu" "F.Mask" "F.Paste")
			(net "GND")
		)
		(pad "55" smd rect
			(at 12.4 -2.19999 270)
			(size 1.1 1.1)
			(layers "F.Cu" "F.Mask" "F.Paste")
			(net "GND")
		)
		(pad "55" smd rect
			(at 14.5 -12.69997 270)
			(size 1.1 1.1)
			(layers "F.Cu" "F.Mask" "F.Paste")
			(net "GND")
		)
		(pad "55" smd rect
			(at 14.5 -10.59998 270)
			(size 1.1 1.1)
			(layers "F.Cu" "F.Mask" "F.Paste")
			(net "GND")
		)
		(pad "55" smd rect
			(at 14.5 -8.49998 270)
			(size 1.1 1.1)
			(layers "F.Cu" "F.Mask" "F.Paste")
			(net "GND")
		)
		(pad "55" smd rect
			(at 14.5 -6.39998 270)
			(size 1.1 1.1)
			(layers "F.Cu" "F.Mask" "F.Paste")
			(net "GND")
		)
		(pad "55" smd rect
			(at 14.5 -4.29999 270)
			(size 1.1 1.1)
			(layers "F.Cu" "F.Mask" "F.Paste")
			(net "GND")
		)
		(pad "55" smd rect
			(at 14.5 -2.19999 270)
			(size 1.1 1.1)
			(layers "F.Cu" "F.Mask" "F.Paste")
			(net "GND")
		)
	)
	(footprint "Vault:TP001V_SMT_100DIA"
		(layer "F.Cu")
		(at 156.4441 118.4631 90)
		(property "Reference" "TP6"
			(at 4.0108 0.07907 90)
			(unlocked yes)
			(layer "F.SilkS")
			(effects
				(font
					(size 0.8 0.8)
					(thickness 0.15)
				)
			)
		)
		(property "Value" "SMT_100DIA"
			(at -2.124202 7.0716 0)
			(unlocked yes)
			(layer "F.SilkS")
			(hide yes)
			(effects
				(font
					(size 1.524 1.524)
					(thickness 0.254)
				)
			)
		)
		(sheetname "ZED-F9T")
		(sheetfile "ZED-F9T.kicad_sch")
		(duplicate_pad_numbers_are_jumpers no)
		(pad "1" smd circle
			(at 1.397 0 90)
			(size 1 1)
			(layers "F.Cu" "F.Mask" "F.Paste")
			(net "NetTP6_1")
			(solder_mask_margin 0.05)
			(solder_paste_margin 0)
			(thermal_bridge_angle 90)
		)
	)
	(footprint "Vault:FP-RMCF0402-IPC_C"
		(layer "F.Cu")
		(at 170.7443 107.7951 -90)
		(property "Reference" "R5"
			(at -1.755 0.02827 270)
			(unlocked yes)
			(layer "F.SilkS")
			(effects
				(font
					(size 0.8 0.8)
					(thickness 0.15)
				)
			)
		)
		(property "Value" "10k"
			(at 2.632122 -15.323605 0)
			(unlocked yes)
			(layer "F.SilkS")
			(hide yes)
			(effects
				(font
					(size 1.524 1.524)
					(thickness 0.254)
				)
			)
		)
		(sheetname "ZED-F9T")
		(sheetfile "ZED-F9T.kicad_sch")
		(duplicate_pad_numbers_are_jumpers no)
		(fp_line
			(start 0.65607 0.675)
			(end -0.65607 0.675)
			(stroke
				(width 0.2)
				(type solid)
			)
			(layer "F.SilkS")
		)
		(fp_line
			(start 0.65607 -0.675)
			(end -0.65607 -0.675)
			(stroke
				(width 0.2)
				(type solid)
			)
			(layer "F.SilkS")
		)
		(fp_line
			(start -0.75607 0.375)
			(end -0.75607 -0.375)
			(stroke
				(width 0.2)
				(type solid)
			)
			(layer "F.CrtYd")
		)
		(fp_line
			(start 0.75607 0.375)
			(end -0.75607 0.375)
			(stroke
				(width 0.2)
				(type solid)
			)
			(layer "F.CrtYd")
		)
		(fp_line
			(start 0.75607 0.375)
			(end 0.75607 -0.375)
			(stroke
				(width 0.2)
				(type solid)
			)
			(layer "F.CrtYd")
		)
		(fp_line
			(start 0.75607 -0.375)
			(end -0.75607 -0.375)
			(stroke
				(width 0.2)
				(type solid)
			)
			(layer "F.CrtYd")
		)
		(fp_line
			(start 0 0.5)
			(end 0 -0.5)
			(stroke
				(width 0.1)
				(type solid)
			)
			(layer "F.Fab")
		)
		(fp_line
			(start -0.75607 0.375)
			(end -0.75607 -0.375)
			(stroke
				(width 0.2)
				(type solid)
			)
			(layer "F.Fab")
		)
		(fp_line
			(start 0.75607 0.375)
			(end -0.75607 0.375)
			(stroke
				(width 0.2)
				(type solid)
			)
			(layer "F.Fab")
		)
		(fp_line
			(start 0.75607 0.375)
			(end 0.75607 -0.375)
			(stroke
				(width 0.2)
				(type solid)
			)
			(layer "F.Fab")
		)
		(fp_line
			(start 0.5 0)
			(end -0.5 0)
			(stroke
				(width 0.1)
				(type solid)
			)
			(layer "F.Fab")
		)
		(fp_line
			(start 0.75607 -0.375)
			(end -0.75607 -0.375)
			(stroke
				(width 0.2)
				(type solid)
			)
			(layer "F.Fab")
		)
		(fp_text user "${REFERENCE}"
			(at -0.00001 0.09647 270)
			(unlocked yes)
			(layer "F.Fab")
			(effects
				(font
					(face "Arial")
					(size 0.63 0.63)
					(thickness 0.1)
				)
				(justify left bottom)
			)
		)
		(pad "1" smd rect
			(at -0.36554 0 270)
			(size 0.58106 0.47247)
			(layers "F.Cu" "F.Mask" "F.Paste")
			(net "RXD")
			(solder_mask_margin 0)
			(solder_paste_margin 0)
		)
		(pad "2" smd rect
			(at 0.36554 0 270)
			(size 0.58106 0.47247)
			(layers "F.Cu" "F.Mask" "F.Paste")
			(net "RXD_IN")
			(solder_mask_margin 0)
			(solder_paste_margin 0)
		)
	)
	(footprint "Vault:FP-RMCF0402-MFG"
		(layer "F.Cu")
		(at 130.5361 109.1921 180)
		(property "Reference" "R10"
			(at -0.022995 -1.52687 0)
			(unlocked yes)
			(layer "F.SilkS")
			(effects
				(font
					(size 0.8 0.8)
					(thickness 0.15)
				)
			)
		)
		(property "Value" "1k"
			(at -0.57117 -2.378202 0)
			(unlocked yes)
			(layer "F.SilkS")
			(hide yes)
			(effects
				(font
					(size 1.524 1.524)
					(thickness 0.254)
				)
			)
		)
		(sheetname "Antenna_Supervisor")
		(sheetfile "Antenna_Supervisor.kicad_sch")
		(duplicate_pad_numbers_are_jumpers no)
		(fp_line
			(start 0.55 0.7)
			(end -0.55 0.7)
			(stroke
				(width 0.2)
				(type solid)
			)
			(layer "F.SilkS")
		)
		(fp_line
			(start 0.55 -0.7)
			(end -0.55 -0.7)
			(stroke
				(width 0.2)
				(type solid)
			)
			(layer "F.SilkS")
		)
		(fp_line
			(start 0.85 0.4)
			(end -0.85 0.4)
			(stroke
				(width 0.2)
				(type solid)
			)
			(layer "F.CrtYd")
		)
		(fp_line
			(start 0.85 -0.4)
			(end 0.85 0.4)
			(stroke
				(width 0.2)
				(type solid)
			)
			(layer "F.CrtYd")
		)
		(fp_line
			(start 0.85 -0.4)
			(end -0.85 -0.4)
			(stroke
				(width 0.2)
				(type solid)
			)
			(layer "F.CrtYd")
		)
		(fp_line
			(start -0.85 -0.4)
			(end -0.85 0.4)
			(stroke
				(width 0.2)
				(type solid)
			)
			(layer "F.CrtYd")
		)
		(fp_line
			(start 0.85 0.4)
			(end -0.85 0.4)
			(stroke
				(width 0.2)
				(type solid)
			)
			(layer "F.Fab")
		)
		(fp_line
			(start 0.85 -0.4)
			(end 0.85 0.4)
			(stroke
				(width 0.2)
				(type solid)
			)
			(layer "F.Fab")
		)
		(fp_line
			(start 0.85 -0.4)
			(end -0.85 -0.4)
			(stroke
				(width 0.2)
				(type solid)
			)
			(layer "F.Fab")
		)
		(fp_line
			(start 0.5 0)
			(end -0.5 0)
			(stroke
				(width 0.1)
				(type solid)
			)
			(layer "F.Fab")
		)
		(fp_line
			(start 0 -0.5)
			(end 0 0.5)
			(stroke
				(width 0.1)
				(type solid)
			)
			(layer "F.Fab")
		)
		(fp_line
			(start -0.85 -0.4)
			(end -0.85 0.4)
			(stroke
				(width 0.2)
				(type solid)
			)
			(layer "F.Fab")
		)
		(fp_text user "${REFERENCE}"
			(at 0.6604 -1.87447 360)
			(unlocked yes)
			(layer "F.Fab")
			(effects
				(font
					(face "Arial")
					(size 0.63 0.63)
					(thickness 0.1)
				)
				(justify left bottom)
			)
		)
		(pad "1" smd rect
			(at -0.5 0 180)
			(size 0.5 0.6)
			(layers "F.Cu" "F.Mask" "F.Paste")
			(net "NetR10_1")
			(solder_mask_margin 0)
			(solder_paste_margin 0)
		)
		(pad "2" smd rect
			(at 0.5 0 180)
			(size 0.5 0.6)
			(layers "F.Cu" "F.Mask" "F.Paste")
			(net "NetQ1_3")
			(solder_mask_margin 0)
			(solder_paste_margin 0)
		)
	)
	(footprint "Vault:FP-RMCF0402-MFG"
		(layer "F.Cu")
		(at 148.8241 94.8411 90)
		(property "Reference" "R1"
			(at 2.055 0.15527 90)
			(unlocked yes)
			(layer "F.SilkS")
			(effects
				(font
					(size 0.8 0.8)
					(thickness 0.15)
				)
			)
		)
		(property "Value" "1k"
			(at -2.378202 0.57117 0)
			(unlocked yes)
			(layer "F.SilkS")
			(hide yes)
			(effects
				(font
					(size 1.524 1.524)
					(thickness 0.254)
				)
			)
		)
		(sheetname "ZED-F9T")
		(sheetfile "ZED-F9T.kicad_sch")
		(duplicate_pad_numbers_are_jumpers no)
		(fp_line
			(start -0.55 -0.7)
			(end 0.55 -0.7)
			(stroke
				(width 0.2)
				(type solid)
			)
			(layer "F.SilkS")
		)
		(fp_line
			(start -0.55 0.7)
			(end 0.55 0.7)
			(stroke
				(width 0.2)
				(type solid)
			)
			(layer "F.SilkS")
		)
		(fp_line
			(start 0.85 -0.4)
			(end 0.85 0.4)
			(stroke
				(width 0.2)
				(type solid)
			)
			(layer "F.CrtYd")
		)
		(fp_line
			(start -0.85 -0.4)
			(end 0.85 -0.4)
			(stroke
				(width 0.2)
				(type solid)
			)
			(layer "F.CrtYd")
		)
		(fp_line
			(start -0.85 -0.4)
			(end -0.85 0.4)
			(stroke
				(width 0.2)
				(type solid)
			)
			(layer "F.CrtYd")
		)
		(fp_line
			(start -0.85 0.4)
			(end 0.85 0.4)
			(stroke
				(width 0.2)
				(type solid)
			)
			(layer "F.CrtYd")
		)
		(fp_line
			(start 0 -0.5)
			(end 0 0.5)
			(stroke
				(width 0.1)
				(type solid)
			)
			(layer "F.Fab")
		)
		(fp_line
			(start 0.85 -0.4)
			(end 0.85 0.4)
			(stroke
				(width 0.2)
				(type solid)
			)
			(layer "F.Fab")
		)
		(fp_line
			(start -0.85 -0.4)
			(end 0.85 -0.4)
			(stroke
				(width 0.2)
				(type solid)
			)
			(layer "F.Fab")
		)
		(fp_line
			(start -0.85 -0.4)
			(end -0.85 0.4)
			(stroke
				(width 0.2)
				(type solid)
			)
			(layer "F.Fab")
		)
		(fp_line
			(start -0.5 0)
			(end 0.5 0)
			(stroke
				(width 0.1)
				(type solid)
			)
			(layer "F.Fab")
		)
		(fp_line
			(start -0.85 0.4)
			(end 0.85 0.4)
			(stroke
				(width 0.2)
				(type solid)
			)
			(layer "F.Fab")
		)
		(fp_text user "${REFERENCE}"
			(at -0.00001 0.10711 90)
			(unlocked yes)
			(layer "F.Fab")
			(effects
				(font
					(face "Arial")
					(size 0.63 0.63)
					(thickness 0.1)
				)
				(justify left bottom)
			)
		)
		(pad "1" smd rect
			(at -0.5 0 90)
			(size 0.5 0.6)
			(layers "F.Cu" "F.Mask" "F.Paste")
			(net "NetC5_1")
			(solder_mask_margin 0)
			(solder_paste_margin 0)
		)
		(pad "2" smd rect
			(at 0.5 0 90)
			(size 0.5 0.6)
			(layers "F.Cu" "F.Mask" "F.Paste")
			(net "VCC")
			(solder_mask_margin 0)
			(solder_paste_margin 0)
		)
	)
	(footprint "Vault:FP-LQG15HH_02-IPC_B"
		(layer "F.Cu")
		(at 127.9961 101.6991 90)
		(property "Reference" "L1"
			(at 1.87673 0.15 0)
			(unlocked yes)
			(layer "F.SilkS")
			(effects
				(font
					(size 0.8 0.8)
					(thickness 0.15)
				)
			)
		)
		(property "Value" "47nH 300mA"
			(at -2.352802 6.23332 0)
			(unlocked yes)
			(layer "F.SilkS")
			(hide yes)
			(effects
				(font
					(size 1.524 1.524)
					(thickness 0.254)
				)
			)
		)
		(sheetname "Antenna_Supervisor")
		(sheetfile "Antenna_Supervisor.kicad_sch")
		(duplicate_pad_numbers_are_jumpers no)
		(fp_line
			(start -0.73624 -0.68623)
			(end 0.73624 -0.68623)
			(stroke
				(width 0.2)
				(type solid)
			)
			(layer "F.SilkS")
		)
		(fp_line
			(start -0.73624 0.68624)
			(end 0.73624 0.68624)
			(stroke
				(width 0.2)
				(type solid)
			)
			(layer "F.SilkS")
		)
		(fp_circle
			(center -1.38624 0)
			(end -1.26124 0)
			(stroke
				(width 0.25)
				(type solid)
			)
			(fill no)
			(layer "F.SilkS")
		)
		(fp_line
			(start 0.88624 -0.43624)
			(end 0.88624 0.43624)
			(stroke
				(width 0.2)
				(type solid)
			)
			(layer "F.CrtYd")
		)
		(fp_line
			(start -0.88624 -0.43624)
			(end 0.88624 -0.43624)
			(stroke
				(width 0.2)
				(type solid)
			)
			(layer "F.CrtYd")
		)
		(fp_line
			(start -0.88624 -0.43624)
			(end -0.88624 0.43624)
			(stroke
				(width 0.2)
				(type solid)
			)
			(layer "F.CrtYd")
		)
		(fp_line
			(start -0.88624 0.43624)
			(end 0.88624 0.43624)
			(stroke
				(width 0.2)
				(type solid)
			)
			(layer "F.CrtYd")
		)
		(fp_line
			(start 0 -0.5)
			(end 0 0.5)
			(stroke
				(width 0.1)
				(type solid)
			)
			(layer "F.Fab")
		)
		(fp_line
			(start 0.88624 -0.43624)
			(end 0.88624 0.43624)
			(stroke
				(width 0.2)
				(type solid)
			)
			(layer "F.Fab")
		)
		(fp_line
			(start -0.88624 -0.43624)
			(end 0.88624 -0.43624)
			(stroke
				(width 0.2)
				(type solid)
			)
			(layer "F.Fab")
		)
		(fp_line
			(start -0.88624 -0.43624)
			(end -0.88624 0.43624)
			(stroke
				(width 0.2)
				(type solid)
			)
			(layer "F.Fab")
		)
		(fp_line
			(start -0.5 0)
			(end 0.5 0)
			(stroke
				(width 0.1)
				(type solid)
			)
			(layer "F.Fab")
		)
		(fp_line
			(start -0.88624 0.43624)
			(end 0.88624 0.43624)
			(stroke
				(width 0.2)
				(type solid)
			)
			(layer "F.Fab")
		)
		(fp_text user "${REFERENCE}"
			(at -0.1016 1.5295 90)
			(unlocked yes)
			(layer "F.Fab")
			(effects
				(font
					(face "Arial")
					(size 0.63 0.63)
					(thickness 0.1)
				)
				(justify left bottom)
			)
		)
		(pad "1" smd rect
			(at -0.42856 0 90)
			(size 0.61535 0.57247)
			(layers "F.Cu" "F.Mask" "F.Paste")
			(net "NetC10_1")
			(solder_mask_margin 0)
			(solder_paste_margin 0)
		)
		(pad "2" smd rect
			(at 0.42857 0 90)
			(size 0.61535 0.57247)
			(layers "F.Cu" "F.Mask" "F.Paste")
			(net "RF_ANT")
			(solder_mask_margin 0)
			(solder_paste_margin 0)
		)
	)
	(footprint "Vault:TP001V_SMT_100DIA"
		(layer "F.Cu")
		(at 141.7121 95.0951 90)
		(property "Reference" "TP3"
			(at 2.436 -0.02253 90)
			(unlocked yes)
			(layer "F.SilkS")
			(effects
				(font
					(size 0.8 0.8)
					(thickness 0.15)
				)
			)
		)
		(property "Value" "SMT_100DIA"
			(at -2.124202 7.0716 0)
			(unlocked yes)
			(layer "F.SilkS")
			(hide yes)
			(effects
				(font
					(size 1.524 1.524)
					(thickness 0.254)
				)
			)
		)
		(sheetname "ZED-F9T")
		(sheetfile "ZED-F9T.kicad_sch")
		(duplicate_pad_numbers_are_jumpers no)
		(pad "1" smd circle
			(at 0 0 90)
			(size 1 1)
			(layers "F.Cu" "F.Mask" "F.Paste")
			(net "NetTP3_1")
			(solder_mask_margin 0.05)
			(solder_paste_margin 0)
			(thermal_bridge_angle 90)
		)
	)
	(footprint "Vault:TP001V_SMT_100DIA"
		(layer "F.Cu")
		(at 144.5061 95.0951 90)
		(property "Reference" "TP1"
			(at 2.436 0.30767 90)
			(unlocked yes)
			(layer "F.SilkS")
			(effects
				(font
					(size 0.8 0.8)
					(thickness 0.15)
				)
			)
		)
		(property "Value" "SMT_100DIA"
			(at -2.124202 7.0716 0)
			(unlocked yes)
			(layer "F.SilkS")
			(hide yes)
			(effects
				(font
					(size 1.524 1.524)
					(thickness 0.254)
				)
			)
		)
		(sheetname "ZED-F9T")
		(sheetfile "ZED-F9T.kicad_sch")
		(duplicate_pad_numbers_are_jumpers no)
		(pad "1" smd circle
			(at 0 0 90)
			(size 1 1)
			(layers "F.Cu" "F.Mask" "F.Paste")
			(net "NetTP1_1")
			(solder_mask_margin 0.05)
			(solder_paste_margin 0)
			(thermal_bridge_angle 90)
		)
	)
	(footprint "Vault:TP001V_SMT_100DIA"
		(layer "F.Cu")
		(at 143.1091 95.0951 90)
		(property "Reference" "TP2"
			(at 2.6138 0.02827 90)
			(unlocked yes)
			(layer "F.SilkS")
			(effects
				(font
					(size 0.8 0.8)
					(thickness 0.15)
				)
			)
		)
		(property "Value" "SMT_100DIA"
			(at -2.124202 7.0716 0)
			(unlocked yes)
			(layer "F.SilkS")
			(hide yes)
			(effects
				(font
					(size 1.524 1.524)
					(thickness 0.254)
				)
			)
		)
		(sheetname "ZED-F9T")
		(sheetfile "ZED-F9T.kicad_sch")
		(duplicate_pad_numbers_are_jumpers no)
		(pad "1" smd circle
			(at 0 0 90)
			(size 1 1)
			(layers "F.Cu" "F.Mask" "F.Paste")
			(net "NetTP2_1")
			(solder_mask_margin 0.05)
			(solder_paste_margin 0)
			(thermal_bridge_angle 90)
		)
	)
	(footprint "Vault:FP-RMCF0402-IPC_C"
		(layer "F.Cu")
		(at 168.6615 107.7951 90)
		(property "Reference" "R6"
			(at 1.755 -0.02827 270)
			(unlocked yes)
			(layer "F.SilkS")
			(effects
				(font
					(size 0.8 0.8)
					(thickness 0.15)
				)
			)
		)
		(property "Value" "10k"
			(at -2.632122 15.323605 0)
			(unlocked yes)
			(layer "F.SilkS")
			(hide yes)
			(effects
				(font
					(size 1.524 1.524)
					(thickness 0.254)
				)
			)
		)
		(sheetname "ZED-F9T")
		(sheetfile "ZED-F9T.kicad_sch")
		(duplicate_pad_numbers_are_jumpers no)
		(fp_line
			(start -0.65607 -0.675)
			(end 0.65607 -0.675)
			(stroke
				(width 0.2)
				(type solid)
			)
			(layer "F.SilkS")
		)
		(fp_line
			(start -0.65607 0.675)
			(end 0.65607 0.675)
			(stroke
				(width 0.2)
				(type solid)
			)
			(layer "F.SilkS")
		)
		(fp_line
			(start 0.75607 -0.375)
			(end 0.75607 0.375)
			(stroke
				(width 0.2)
				(type solid)
			)
			(layer "F.CrtYd")
		)
		(fp_line
			(start -0.75607 -0.375)
			(end 0.75607 -0.375)
			(stroke
				(width 0.2)
				(type solid)
			)
			(layer "F.CrtYd")
		)
		(fp_line
			(start -0.75607 -0.375)
			(end -0.75607 0.375)
			(stroke
				(width 0.2)
				(type solid)
			)
			(layer "F.CrtYd")
		)
		(fp_line
			(start -0.75607 0.375)
			(end 0.75607 0.375)
			(stroke
				(width 0.2)
				(type solid)
			)
			(layer "F.CrtYd")
		)
		(fp_line
			(start 0 -0.5)
			(end 0 0.5)
			(stroke
				(width 0.1)
				(type solid)
			)
			(layer "F.Fab")
		)
		(fp_line
			(start 0.75607 -0.375)
			(end 0.75607 0.375)
			(stroke
				(width 0.2)
				(type solid)
			)
			(layer "F.Fab")
		)
		(fp_line
			(start -0.75607 -0.375)
			(end 0.75607 -0.375)
			(stroke
				(width 0.2)
				(type solid)
			)
			(layer "F.Fab")
		)
		(fp_line
			(start -0.75607 -0.375)
			(end -0.75607 0.375)
			(stroke
				(width 0.2)
				(type solid)
			)
			(layer "F.Fab")
		)
		(fp_line
			(start -0.5 0)
			(end 0.5 0)
			(stroke
				(width 0.1)
				(type solid)
			)
			(layer "F.Fab")
		)
		(fp_line
			(start -0.75607 0.375)
			(end 0.75607 0.375)
			(stroke
				(width 0.2)
				(type solid)
			)
			(layer "F.Fab")
		)
		(fp_text user "${REFERENCE}"
			(at -0.00001 0.09647 90)
			(unlocked yes)
			(layer "F.Fab")
			(effects
				(font
					(face "Arial")
					(size 0.63 0.63)
					(thickness 0.1)
				)
				(justify left bottom)
			)
		)
		(pad "1" smd rect
			(at -0.36554 0 90)
			(size 0.58106 0.47247)
			(layers "F.Cu" "F.Mask" "F.Paste")
			(net "TXD_OUT")
			(solder_mask_margin 0)
			(solder_paste_margin 0)
		)
		(pad "2" smd rect
			(at 0.36554 0 90)
			(size 0.58106 0.47247)
			(layers "F.Cu" "F.Mask" "F.Paste")
			(net "TXD")
			(solder_mask_margin 0)
			(solder_paste_margin 0)
		)
	)
	(footprint "Vault:TP001V_SMT_100DIA"
		(layer "F.Cu")
		(at 150.6021 95.0951 90)
		(property "Reference" "TP5"
			(at 2.6138 0.12987 90)
			(unlocked yes)
			(layer "F.SilkS")
			(effects
				(font
					(size 0.8 0.8)
					(thickness 0.15)
				)
			)
		)
		(property "Value" "SMT_100DIA"
			(at -2.124202 7.0716 0)
			(unlocked yes)
			(layer "F.SilkS")
			(hide yes)
			(effects
				(font
					(size 1.524 1.524)
					(thickness 0.254)
				)
			)
		)
		(sheetname "ZED-F9T")
		(sheetfile "ZED-F9T.kicad_sch")
		(duplicate_pad_numbers_are_jumpers no)
		(pad "1" smd circle
			(at 0 0 90)
			(size 1 1)
			(layers "F.Cu" "F.Mask" "F.Paste")
			(net "NetTP5_1")
			(solder_mask_margin 0.05)
			(solder_paste_margin 0)
			(thermal_bridge_angle 90)
		)
	)
	(footprint "Vault:DCK0005A_N"
		(layer "F.Cu")
		(at 130.4091 104.4931 90)
		(property "Reference" "U4"
			(at 2.30853 -0.104 0)
			(unlocked yes)
			(layer "F.SilkS")
			(effects
				(font
					(size 0.8 0.8)
					(thickness 0.15)
				)
			)
		)
		(property "Value" "LPV511MGX/NOPB"
			(at -2.962402 8.848615 0)
			(unlocked yes)
			(layer "F.SilkS")
			(hide yes)
			(effects
				(font
					(size 1.524 1.524)
					(thickness 0.254)
				)
			)
		)
		(sheetname "Antenna_Supervisor")
		(sheetfile "Antenna_Supervisor.kicad_sch")
		(duplicate_pad_numbers_are_jumpers no)
		(fp_line
			(start 0.3 -1.1)
			(end 0.3 1.1)
			(stroke
				(width 0.2)
				(type solid)
			)
			(layer "F.SilkS")
		)
		(fp_line
			(start -0.3 -1.1)
			(end 0.3 -1.1)
			(stroke
				(width 0.2)
				(type solid)
			)
			(layer "F.SilkS")
		)
		(fp_line
			(start -0.3 -1.1)
			(end -0.3 1.1)
			(stroke
				(width 0.2)
				(type solid)
			)
			(layer "F.SilkS")
		)
		(fp_line
			(start -0.3 1.1)
			(end 0.3 1.1)
			(stroke
				(width 0.2)
				(type solid)
			)
			(layer "F.SilkS")
		)
		(fp_circle
			(center -1.125 -1.4)
			(end -1 -1.4)
			(stroke
				(width 0.25)
				(type solid)
			)
			(fill no)
			(layer "F.SilkS")
		)
		(fp_line
			(start 1.8 -1.35)
			(end 1.8 1.35)
			(stroke
				(width 0.05)
				(type solid)
			)
			(layer "F.CrtYd")
		)
		(fp_line
			(start -1.8 -1.35)
			(end 1.8 -1.35)
			(stroke
				(width 0.05)
				(type solid)
			)
			(layer "F.CrtYd")
		)
		(fp_line
			(start -1.8 -1.35)
			(end -1.8 1.35)
			(stroke
				(width 0.05)
				(type solid)
			)
			(layer "F.CrtYd")
		)
		(fp_line
			(start 0 -0.5)
			(end 0 0.5)
			(stroke
				(width 0.1)
				(type solid)
			)
			(layer "F.CrtYd")
		)
		(fp_line
			(start -0.5 0)
			(end 0.5 0)
			(stroke
				(width 0.1)
				(type solid)
			)
			(layer "F.CrtYd")
		)
		(fp_line
			(start -1.8 1.35)
			(end 1.8 1.35)
			(stroke
				(width 0.05)
				(type solid)
			)
			(layer "F.CrtYd")
		)
		(pad "1" smd roundrect
			(at -1.125 -0.65 180)
			(size 0.4 0.85)
			(layers "F.Cu" "F.Mask" "F.Paste")
			(roundrect_rratio 0.125)
			(net "NetU3_1")
		)
		(pad "2" smd roundrect
			(at -1.125 0 180)
			(size 0.4 0.85)
			(layers "F.Cu" "F.Mask" "F.Paste")
			(roundrect_rratio 0.125)
			(net "GND")
		)
		(pad "3" smd roundrect
			(at -1.125 0.65 180)
			(size 0.4 0.85)
			(layers "F.Cu" "F.Mask" "F.Paste")
			(roundrect_rratio 0.125)
			(net "NetR10_1")
		)
		(pad "4" smd roundrect
			(at 1.125 0.65 180)
			(size 0.4 0.85)
			(layers "F.Cu" "F.Mask" "F.Paste")
			(roundrect_rratio 0.125)
			(net "NetC10_1")
		)
		(pad "5" smd roundrect
			(at 1.125 -0.65 180)
			(size 0.4 0.85)
			(layers "F.Cu" "F.Mask" "F.Paste")
			(roundrect_rratio 0.125)
			(net "VCC")
		)
	)
	(footprint "Vault:RESC1608X055N"
		(layer "F.Cu")
		(at 127.9961 108.4301 90)
		(property "Reference" "R12"
			(at -2.26347 -0.231005 0)
			(unlocked yes)
			(layer "F.SilkS")
			(effects
				(font
					(size 0.8 0.8)
					(thickness 0.15)
				)
			)
		)
		(property "Value" "Vishay_RCP0603W25R0GEB"
			(at -2.378202 15.323605 0)
			(unlocked yes)
			(layer "F.SilkS")
			(hide yes)
			(effects
				(font
					(size 1.524 1.524)
					(thickness 0.254)
				)
			)
		)
		(sheetname "Antenna_Supervisor")
		(sheetfile "Antenna_Supervisor.kicad_sch")
		(duplicate_pad_numbers_are_jumpers no)
		(fp_line
			(start 1.5 -0.75)
			(end 1.5 0.75)
			(stroke
				(width 0.1)
				(type solid)
			)
			(layer "F.CrtYd")
		)
		(fp_line
			(start -1.5 -0.75)
			(end 1.5 -0.75)
			(stroke
				(width 0.1)
				(type solid)
			)
			(layer "F.CrtYd")
		)
		(fp_line
			(start -1.5 -0.75)
			(end -1.5 0.75)
			(stroke
				(width 0.1)
				(type solid)
			)
			(layer "F.CrtYd")
		)
		(fp_line
			(start -1.5 0.75)
			(end 1.5 0.75)
			(stroke
				(width 0.1)
				(type solid)
			)
			(layer "F.CrtYd")
		)
		(fp_line
			(start 0.80017 -0.40012)
			(end 0.80017 0.39984)
			(stroke
				(width 0.05)
				(type solid)
			)
			(layer "F.Fab")
		)
		(fp_line
			(start -0.79991 -0.40012)
			(end 0.80017 -0.40012)
			(stroke
				(width 0.05)
				(type solid)
			)
			(layer "F.Fab")
		)
		(fp_line
			(start -0.79991 -0.40012)
			(end -0.79991 0.39984)
			(stroke
				(width 0.05)
				(type solid)
			)
			(layer "F.Fab")
		)
		(fp_line
			(start -0.79991 0.39984)
			(end 0.80017 0.39984)
			(stroke
				(width 0.05)
				(type solid)
			)
			(layer "F.Fab")
		)
		(fp_text_box "${REFERENCE}"
			(start -1.09004 -0.20727)
			(end 1.09004 0.20726)
			(margins 0 0 0 0)
			(layer "F.Fab")
			(effects
				(font
					(face "Arial")
					(size 0.315 0.315)
					(thickness 0.254)
				)
				(justify top)
			)
			(border no)
			(stroke
				(width 0.1)
				(type default)
			)
			(knockout no)
		)
		(pad "1" smd rect
			(at -0.8 0 90)
			(size 0.9 1)
			(layers "F.Cu" "F.Mask" "F.Paste")
			(net "NetQ1_3")
			(solder_mask_margin 0.05)
			(solder_paste_margin 0)
		)
		(pad "2" smd rect
			(at 0.8 0 90)
			(size 0.9 1)
			(layers "F.Cu" "F.Mask" "F.Paste")
			(net "NetC10_1")
			(solder_mask_margin 0.05)
			(solder_paste_margin 0)
		)
	)
	(footprint "Vault:SOT23_3pins_300x140x112"
		(layer "F.Cu")
		(at 130.0281 113.1291)
		(property "Reference" "Q1"
			(at -2.7202 1.32367 0)
			(unlocked yes)
			(layer "F.SilkS")
			(effects
				(font
					(size 0.8 0.8)
					(thickness 0.15)
				)
			)
		)
		(property "Value" "onsemi_NTR2101PT1G"
			(at 11.61631 3.673602 0)
			(unlocked yes)
			(layer "F.SilkS")
			(hide yes)
			(effects
				(font
					(size 1.524 1.524)
					(thickness 0.254)
				)
			)
		)
		(sheetname "Antenna_Supervisor")
		(sheetfile "Antenna_Supervisor.kicad_sch")
		(duplicate_pad_numbers_are_jumpers no)
		(fp_line
			(start -1.7 -0.9)
			(end -0.7 -0.9)
			(stroke
				(width 0.1)
				(type solid)
			)
			(layer "F.SilkS")
		)
		(fp_line
			(start -1.7 0.7)
			(end -1.7 -0.9)
			(stroke
				(width 0.1)
				(type solid)
			)
			(layer "F.SilkS")
		)
		(fp_line
			(start -0.3 0.9)
			(end 0.3 0.9)
			(stroke
				(width 0.1)
				(type solid)
			)
			(layer "F.SilkS")
		)
		(fp_line
			(start 0.7 -0.9)
			(end 1.7 -0.9)
			(stroke
				(width 0.1)
				(type solid)
			)
			(layer "F.SilkS")
		)
		(fp_line
			(start 1.7 0.7)
			(end 1.7 -0.9)
			(stroke
				(width 0.1)
				(type solid)
			)
			(layer "F.SilkS")
		)
		(fp_circle
			(center -1 1.9)
			(end -1 1.8)
			(stroke
				(width 0.2)
				(type solid)
			)
			(fill no)
			(layer "F.SilkS")
		)
		(fp_line
			(start -1.8 -1.8)
			(end 1.8 -1.8)
			(stroke
				(width 0.1)
				(type solid)
			)
			(layer "F.CrtYd")
		)
		(fp_line
			(start -1.8 1.8)
			(end -1.8 -1.8)
			(stroke
				(width 0.1)
				(type solid)
			)
			(layer "F.CrtYd")
		)
		(fp_line
			(start -1.8 1.8)
			(end 1.8 1.8)
			(stroke
				(width 0.1)
				(type solid)
			)
			(layer "F.CrtYd")
		)
		(fp_line
			(start 1.8 1.8)
			(end 1.8 -1.8)
			(stroke
				(width 0.1)
				(type solid)
			)
			(layer "F.CrtYd")
		)
		(fp_line
			(start -1.5 -0.7)
			(end 1.5 -0.7)
			(stroke
				(width 0.1)
				(type solid)
			)
			(layer "F.Fab")
		)
		(fp_line
			(start -1.5 0.7)
			(end -1.5 -0.7)
			(stroke
				(width 0.1)
				(type solid)
			)
			(layer "F.Fab")
		)
		(fp_line
			(start -1.5 0.7)
			(end 1.5 0.7)
			(stroke
				(width 0.1)
				(type solid)
			)
			(layer "F.Fab")
		)
		(fp_line
			(start -1.205 1.2)
			(end -1.205 0.705)
			(stroke
				(width 0.1)
				(type solid)
			)
			(layer "F.Fab")
		)
		(fp_line
			(start -1.205 1.2)
			(end -0.695 1.2)
			(stroke
				(width 0.1)
				(type solid)
			)
			(layer "F.Fab")
		)
		(fp_line
			(start -0.695 1.2)
			(end -0.695 0.705)
			(stroke
				(width 0.1)
				(type solid)
			)
			(layer "F.Fab")
		)
		(fp_line
			(start -0.255 -1.2)
			(end -0.255 -0.705)
			(stroke
				(width 0.1)
				(type solid)
			)
			(layer "F.Fab")
		)
		(fp_line
			(start -0.255 -1.2)
			(end 0.255 -1.2)
			(stroke
				(width 0.1)
				(type solid)
			)
			(layer "F.Fab")
		)
		(fp_line
			(start 0.255 -0.705)
			(end 0.255 -1.2)
			(stroke
				(width 0.1)
				(type solid)
			)
			(layer "F.Fab")
		)
		(fp_line
			(start 0.695 1.2)
			(end 0.695 0.705)
			(stroke
				(width 0.1)
				(type solid)
			)
			(layer "F.Fab")
		)
		(fp_line
			(start 0.695 1.2)
			(end 1.205 1.2)
			(stroke
				(width 0.1)
				(type solid)
			)
			(layer "F.Fab")
		)
		(fp_line
			(start 1.205 1.2)
			(end 1.205 0.705)
			(stroke
				(width 0.1)
				(type solid)
			)
			(layer "F.Fab")
		)
		(fp_line
			(start 1.5 0.7)
			(end 1.5 -0.7)
			(stroke
				(width 0.1)
				(type solid)
			)
			(layer "F.Fab")
		)
		(fp_text_box "${REFERENCE}"
			(start -1.09004 -0.20727)
			(end 1.09004 0.20726)
			(margins 0 0 0 0)
			(layer "F.Fab")
			(effects
				(font
					(face "Arial")
					(size 0.315 0.315)
					(thickness 0.254)
				)
				(justify top)
			)
			(border no)
			(stroke
				(width 0.1)
				(type default)
			)
			(knockout no)
		)
		(pad "1" smd rect
			(at -0.95 1)
			(size 0.8 0.9)
			(layers "F.Cu" "F.Mask" "F.Paste")
			(net "NetQ1_1")
			(solder_mask_margin 0.05)
			(solder_paste_margin 0)
		)
		(pad "2" smd rect
			(at 0.95 1)
			(size 0.8 0.9)
			(layers "F.Cu" "F.Mask" "F.Paste")
			(net "VCC_ANT")
			(solder_mask_margin 0.05)
			(solder_paste_margin 0)
		)
		(pad "3" smd rect
			(at 0 -1)
			(size 0.8 0.9)
			(layers "F.Cu" "F.Mask" "F.Paste")
			(net "NetQ1_3")
			(solder_mask_margin 0.05)
			(solder_paste_margin 0)
		)
	)
	(footprint "Vault:CAPC1005X055N"
		(layer "F.Cu")
		(at 156.4441 105.6361)
		(property "Reference" "C3"
			(at 2.055 0.15527 0)
			(unlocked yes)
			(layer "F.SilkS")
			(effects
				(font
					(size 0.8 0.8)
					(thickness 0.15)
				)
			)
		)
		(property "Value" "Murata_GRM155R61E105KA12D"
			(at 17.659825 2.124202 0)
			(unlocked yes)
			(layer "F.SilkS")
			(hide yes)
			(effects
				(font
					(size 1.524 1.524)
					(thickness 0.254)
				)
			)
		)
		(sheetname "ZED-F9T")
		(sheetfile "ZED-F9T.kicad_sch")
		(duplicate_pad_numbers_are_jumpers no)
		(fp_line
			(start -0.95 -0.5)
			(end 0.95 -0.5)
			(stroke
				(width 0.1)
				(type solid)
			)
			(layer "F.CrtYd")
		)
		(fp_line
			(start -0.95 0.5)
			(end -0.95 -0.5)
			(stroke
				(width 0.1)
				(type solid)
			)
			(layer "F.CrtYd")
		)
		(fp_line
			(start -0.95 0.5)
			(end 0.95 0.5)
			(stroke
				(width 0.1)
				(type solid)
			)
			(layer "F.CrtYd")
		)
		(fp_line
			(start 0.95 0.5)
			(end 0.95 -0.5)
			(stroke
				(width 0.1)
				(type solid)
			)
			(layer "F.CrtYd")
		)
		(fp_line
			(start -0.5 -0.25)
			(end 0.5 -0.25)
			(stroke
				(width 0.05)
				(type solid)
			)
			(layer "F.Fab")
		)
		(fp_line
			(start -0.5 0.25)
			(end -0.5 -0.25)
			(stroke
				(width 0.05)
				(type solid)
			)
			(layer "F.Fab")
		)
		(fp_line
			(start -0.5 0.25)
			(end 0.5 0.25)
			(stroke
				(width 0.05)
				(type solid)
			)
			(layer "F.Fab")
		)
		(fp_line
			(start 0.5 0.25)
			(end 0.5 -0.25)
			(stroke
				(width 0.05)
				(type solid)
			)
			(layer "F.Fab")
		)
		(fp_text_box "${REFERENCE}"
			(start -1.09004 -0.20727)
			(end 1.09004 0.20726)
			(margins 0 0 0 0)
			(layer "F.Fab")
			(effects
				(font
					(face "Arial")
					(size 0.315 0.315)
					(thickness 0.254)
				)
				(justify top)
			)
			(border no)
			(stroke
				(width 0.1)
				(type default)
			)
			(knockout no)
		)
		(pad "1" smd rect
			(at -0.46 0)
			(size 0.6 0.62)
			(layers "F.Cu" "F.Mask" "F.Paste")
			(net "VCC")
			(solder_mask_margin 0.05)
			(solder_paste_margin 0)
		)
		(pad "2" smd rect
			(at 0.46 0)
			(size 0.6 0.62)
			(layers "F.Cu" "F.Mask" "F.Paste")
			(net "GND")
			(solder_mask_margin 0.05)
			(solder_paste_margin 0)
		)
	)
	(footprint "Vault:TP001V_SMT_100DIA"
		(layer "F.Cu")
		(at 159.2381 115.6691 90)
		(property "Reference" "TP8"
			(at 1.039 0.25687 90)
			(unlocked yes)
			(layer "F.SilkS")
			(effects
				(font
					(size 0.8 0.8)
					(thickness 0.15)
				)
			)
		)
		(property "Value" "SMT_100DIA"
			(at -2.124202 7.0716 0)
			(unlocked yes)
			(layer "F.SilkS")
			(hide yes)
			(effects
				(font
					(size 1.524 1.524)
					(thickness 0.254)
				)
			)
		)
		(sheetname "ZED-F9T")
		(sheetfile "ZED-F9T.kicad_sch")
		(duplicate_pad_numbers_are_jumpers no)
		(pad "1" smd circle
			(at -1.397 0 90)
			(size 1 1)
			(layers "F.Cu" "F.Mask" "F.Paste")
			(net "NetTP8_1")
			(solder_mask_margin 0.05)
			(solder_paste_margin 0)
			(thermal_bridge_angle 90)
		)
	)
	(gr_line
		(start 114.9131 90.2001)
		(end 114.9151 119.8311)
		(stroke
			(width 0.05)
			(type solid)
		)
		(layer "Edge.Cuts")
	)
	(gr_line
		(start 114.9131 90.200104)
		(end 114.9131 90.2001)
		(stroke
			(width 0.05)
			(type solid)
		)
		(layer "Edge.Cuts")
	)
	(gr_arc
		(start 114.9131 90.200104)
		(mid 115.226421 89.443127)
		(end 115.983105 89.1291)
		(stroke
			(width 0.05)
			(type solid)
		)
		(layer "Edge.Cuts")
	)
	(gr_arc
		(start 115.960101 120.8761)
		(mid 115.221174 120.570027)
		(end 114.9151 119.8311)
		(stroke
			(width 0.05)
			(type solid)
		)
		(layer "Edge.Cuts")
	)
	(gr_line
		(start 115.960101 120.8761)
		(end 115.9601 120.8761)
		(stroke
			(width 0.05)
			(type solid)
		)
		(layer "Edge.Cuts")
	)
	(gr_line
		(start 115.9601 120.8761)
		(end 181.0681 120.8801)
		(stroke
			(width 0.05)
			(type solid)
		)
		(layer "Edge.Cuts")
	)
	(gr_arc
		(start 116.2161 91.9801)
		(mid 116.670084 90.884084)
		(end 117.7661 90.4301)
		(stroke
			(width 0.05)
			(type solid)
		)
		(layer "Edge.Cuts")
	)
	(gr_arc
		(start 116.2161 117.9801)
		(mid 116.67007 116.88407)
		(end 117.7661 116.4301)
		(stroke
			(width 0.05)
			(type solid)
		)
		(layer "Edge.Cuts")
	)
	(gr_arc
		(start 117.7661 90.4301)
		(mid 118.862116 90.884084)
		(end 119.3161 91.9801)
		(stroke
			(width 0.05)
			(type solid)
		)
		(layer "Edge.Cuts")
	)
	(gr_arc
		(start 117.7661 93.5301)
		(mid 116.670084 93.076116)
		(end 116.2161 91.9801)
		(stroke
			(width 0.05)
			(type solid)
		)
		(layer "Edge.Cuts")
	)
	(gr_arc
		(start 117.7661 116.4301)
		(mid 118.862116 116.884084)
		(end 119.3161 117.9801)
		(stroke
			(width 0.05)
			(type solid)
		)
		(layer "Edge.Cuts")
	)
	(gr_arc
		(start 117.7661 119.5301)
		(mid 116.670084 119.076116)
		(end 116.2161 117.9801)
		(stroke
			(width 0.05)
			(type solid)
		)
		(layer "Edge.Cuts")
	)
	(gr_arc
		(start 119.3161 91.9801)
		(mid 118.862116 93.076116)
		(end 117.7661 93.5301)
		(stroke
			(width 0.05)
			(type solid)
		)
		(layer "Edge.Cuts")
	)
	(gr_arc
		(start 119.3161 117.9801)
		(mid 118.86213 119.07613)
		(end 117.7661 119.5301)
		(stroke
			(width 0.05)
			(type solid)
		)
		(layer "Edge.Cuts")
	)
	(gr_arc
		(start 176.7161 91.9801)
		(mid 177.17007 90.88407)
		(end 178.2661 90.4301)
		(stroke
			(width 0.05)
			(type solid)
		)
		(layer "Edge.Cuts")
	)
	(gr_arc
		(start 176.7161 117.9801)
		(mid 177.17007 116.88407)
		(end 178.2661 116.4301)
		(stroke
			(width 0.05)
			(type solid)
		)
		(layer "Edge.Cuts")
	)
	(gr_arc
		(start 178.2661 90.4301)
		(mid 179.36213 90.88407)
		(end 179.8161 91.9801)
		(stroke
			(width 0.05)
			(type solid)
		)
		(layer "Edge.Cuts")
	)
	(gr_arc
		(start 178.2661 93.5301)
		(mid 177.17007 93.07613)
		(end 176.7161 91.9801)
		(stroke
			(width 0.05)
			(type solid)
		)
		(layer "Edge.Cuts")
	)
	(gr_arc
		(start 178.2661 116.4301)
		(mid 179.36213 116.88407)
		(end 179.8161 117.9801)
		(stroke
			(width 0.05)
			(type solid)
		)
		(layer "Edge.Cuts")
	)
	(gr_arc
		(start 178.2661 119.5301)
		(mid 177.17007 119.07613)
		(end 176.7161 117.9801)
		(stroke
			(width 0.05)
			(type solid)
		)
		(layer "Edge.Cuts")
	)
	(gr_arc
		(start 179.8161 91.9801)
		(mid 179.36213 93.07613)
		(end 178.2661 93.5301)
		(stroke
			(width 0.05)
			(type solid)
		)
		(layer "Edge.Cuts")
	)
	(gr_arc
		(start 179.8161 117.9801)
		(mid 179.36213 119.07613)
		(end 178.2661 119.5301)
		(stroke
			(width 0.05)
			(type solid)
		)
		(layer "Edge.Cuts")
	)
	(gr_line
		(start 181.009096 89.1271)
		(end 181.0091 89.1271)
		(stroke
			(width 0.05)
			(type solid)
		)
		(layer "Edge.Cuts")
	)
	(gr_arc
		(start 181.009096 89.1271)
		(mid 181.772436 89.443056)
		(end 182.0891 90.206103)
		(stroke
			(width 0.05)
			(type solid)
		)
		(layer "Edge.Cuts")
	)
	(gr_line
		(start 181.0091 89.1271)
		(end 115.983105 89.1291)
		(stroke
			(width 0.05)
			(type solid)
		)
		(layer "Edge.Cuts")
	)
	(gr_arc
		(start 182.0861 119.8611)
		(mid 181.78801 120.581303)
		(end 181.0681 120.8801)
		(stroke
			(width 0.05)
			(type solid)
		)
		(layer "Edge.Cuts")
	)
	(gr_line
		(start 182.0861 119.8611)
		(end 182.0891 90.206103)
		(stroke
			(width 0.05)
			(type solid)
		)
		(layer "Edge.Cuts")
	)
	(segment
		(start 175.8497 100.7)
		(end 175.98434 100.56536)
		(width 0.2032)
		(layer "F.Cu")
		(net "NetDS1_K")
	)
	(segment
		(start 177.2031 99.4009)
		(end 178.1865 99.4009)
		(width 0.2032)
		(layer "F.Cu")
		(net "NetDS1_K")
	)
	(segment
		(start 175.98434 100.56536)
		(end 176.03863 100.56536)
		(width 0.2032)
		(layer "F.Cu")
		(net "NetDS1_K")
	)
	(segment
		(start 175.8497 100.7543)
		(end 175.8497 100.7)
		(width 0.2032)
		(layer "F.Cu")
		(net "NetDS1_K")
	)
	(segment
		(start 176.03863 100.56536)
		(end 177.2031 99.4009)
		(width 0.2032)
		(layer "F.Cu")
		(net "NetDS1_K")
	)
	(segment
		(start 129.7591 105.6181)
		(end 129.7591 105.45862)
		(width 0.2032)
		(layer "F.Cu")
		(net "NetU3_1")
	)
	(segment
		(start 129.39662 105.36022)
		(end 129.6607 105.36022)
		(width 0.2032)
		(layer "F.Cu")
		(net "NetU3_1")
	)
	(segment
		(start 133.1271 105.3179)
		(end 133.1271 104.5949)
		(width 0.2032)
		(layer "F.Cu")
		(net "NetU3_1")
	)
	(segment
		(start 128.8343 104.7979)
		(end 129.39662 105.36022)
		(width 0.2032)
		(layer "F.Cu")
		(net "NetU3_1")
	)
	(segment
		(start 132.5681 104.0359)
		(end 133.1271 104.5949)
		(width 0.2032)
		(layer "F.Cu")
		(net "NetU3_1")
	)
	(segment
		(start 129.6607 105.36022)
		(end 129.7591 105.45862)
		(width 0.2032)
		(layer "F.Cu")
		(net "NetU3_1")
	)
	(via
		(at 132.5681 104.0359)
		(size 0.6096)
		(drill 0.3048)
		(layers "F.Cu" "B.Cu")
		(locked yes)
		(tenting
			(front yes)
			(back no)
		)
		(net "NetU3_1")
	)
	(via
		(at 128.8343 104.7979)
		(size 0.6096)
		(drill 0.3048)
		(layers "F.Cu" "B.Cu")
		(locked yes)
		(tenting
			(front yes)
			(back no)
		)
		(net "NetU3_1")
	)
	(segment
		(start 129.5963 104.0359)
		(end 132.5681 104.0359)
		(width 0.2032)
		(layer "In1.Cu")
		(net "NetU3_1")
	)
	(segment
		(start 128.8343 104.7979)
		(end 129.5963 104.0359)
		(width 0.2032)
		(layer "In1.Cu")
		(net "NetU3_1")
	)
	(segment
		(start 140.28657 119.0473)
		(end 158.7612 119.0473)
		(width 0.508)
		(layer "F.Cu")
		(net "VCC")
	)
	(segment
		(start 136.01514 105.2441)
		(end 136.08894 105.3179)
		(width 0.1524)
		(layer "F.Cu")
		(net "VCC")
	)
	(segment
		(start 161.9738 115.8347)
		(end 162.36197 115.8347)
		(width 0.508)
		(layer "F.Cu")
		(net "VCC")
	)
	(segment
		(start 167.65196 112.54053)
		(end 167.70753 112.5961)
		(width 0.508)
		(layer "F.Cu")
		(net "VCC")
	)
	(segment
		(start 135.8193 105.0011)
		(end 135.92586 105.0011)
		(width 0.1524)
		(layer "F.Cu")
		(net "VCC")
	)
	(segment
		(start 133.72071 102.5367)
		(end 133.81878 102.63477)
		(width 0.508)
		(layer "F.Cu")
		(net "VCC")
	)
	(segment
		(start 156.0301 104.1931)
		(end 156.0301 103.9927)
		(width 0.508)
		(layer "F.Cu")
		(net "VCC")
	)
	(segment
		(start 169.82835 100.47834)
		(end 170.05694 100.47834)
		(width 0.2032)
		(layer "F.Cu")
		(net "VCC")
	)
	(segment
		(start 168.55528 103.15028)
		(end 168.8187 103.4137)
		(width 0.508)
		(layer "F.Cu")
		(net "VCC")
	)
	(segment
		(start 134.23914 103.3274)
		(end 135.33025 103.3274)
		(width 0.508)
		(layer "F.Cu")
		(net "VCC")
	)
	(segment
		(start 162.4131 104.11001)
		(end 162.4639 104.16081)
		(width 0.508)
		(layer "F.Cu")
		(net "VCC")
	)
	(segment
		(start 166.8327 109.8017)
		(end 166.8835 109.8525)
		(width 0.508)
		(layer "F.Cu")
		(net "VCC")
	)
	(segment
		(start 162.4131 104.11001)
		(end 162.4131 104.0947)
		(width 0.508)
		(layer "F.Cu")
		(net "VCC")
	)
	(segment
		(start 131.33502 104.9391)
		(end 131.5131 105.11718)
		(width 0.2032)
		(layer "F.Cu")
		(net "VCC")
	)
	(segment
		(start 133.81878 102.63477)
		(end 133.87946 102.63477)
		(width 0.508)
		(layer "F.Cu")
		(net "VCC")
	)
	(segment
		(start 129.8131 103.1971)
		(end 129.9301 103.1971)
		(width 0.508)
		(layer "F.Cu")
		(net "VCC")
	)
	(segment
		(start 135.5225 103.3159)
		(end 135.5225 103.2739)
		(width 0.508)
		(layer "F.Cu")
		(net "VCC")
	)
	(segment
		(start 165.15916 104.01127)
		(end 165.15916 103.54608)
		(width 0.508)
		(layer "F.Cu")
		(net "VCC")
	)
	(segment
		(start 167.62447 112.54053)
		(end 167.65196 112.54053)
		(width 0.508)
		(layer "F.Cu")
		(net "VCC")
	)
	(segment
		(start 155.9841 109.2021)
		(end 156.1977 109.4157)
		(width 0.508)
		(layer "F.Cu")
		(net "VCC")
	)
	(segment
		(start 156.1977 109.67043)
		(end 162.36197 115.8347)
		(width 0.508)
		(layer "F.Cu")
		(net "VCC")
	)
	(segment
		(start 149.8909 92.6313)
		(end 161.9813 92.6313)
		(width 0.2032)
		(layer "F.Cu")
		(net "VCC")
	)
	(segment
		(start 165.2833 104.1629)
		(end 165.2833 104.13541)
		(width 0.508)
		(layer "F.Cu")
		(net "VCC")
	)
	(segment
		(start 129.7591 103.2511)
		(end 129.8131 103.1971)
		(width 0.508)
		(layer "F.Cu")
		(net "VCC")
	)
	(segment
		(start 156.70997 103.2485)
		(end 161.5669 103.2485)
		(width 0.508)
		(layer "F.Cu")
		(net "VCC")
	)
	(segment
		(start 162.4639 104.1883)
		(end 162.4639 104.16081)
		(width 0.508)
		(layer "F.Cu")
		(net "VCC")
	)
	(segment
		(start 167.8995 102.5627)
		(end 167.91894 102.58214)
		(width 0.508)
		(layer "F.Cu")
		(net "VCC")
	)
	(segment
		(start 162.36197 115.8347)
		(end 165.7577 115.8347)
		(width 0.508)
		(layer "F.Cu")
		(net "VCC")
	)
	(segment
		(start 165.15916 104.01127)
		(end 165.2833 104.13541)
		(width 0.508)
		(layer "F.Cu")
		(net "VCC")
	)
	(segment
		(start 165.7577 114.4073)
		(end 167.62447 112.54053)
		(width 0.508)
		(layer "F.Cu")
		(net "VCC")
	)
	(segment
		(start 170.7745 103.4557)
		(end 170.7785 103.4597)
		(width 0.508)
		(layer "F.Cu")
		(net "VCC")
	)
	(segment
		(start 130.5905 102.5367)
		(end 133.72071 102.5367)
		(width 0.508)
		(layer "F.Cu")
		(net "VCC")
	)
	(segment
		(start 134.2069 103.29517)
		(end 134.2069 102.96221)
		(width 0.508)
		(layer "F.Cu")
		(net "VCC")
	)
	(segment
		(start 129.8575 103.6915)
		(end 130.0393 103.6915)
		(width 0.2032)
		(layer "F.Cu")
		(net "VCC")
	)
	(segment
		(start 155.9841 104.2391)
		(end 156.0301 104.1931)
		(width 0.508)
		(layer "F.Cu")
		(net "VCC")
	)
	(segment
		(start 165.7577 115.8347)
		(end 165.7577 114.4073)
		(width 0.508)
		(layer "F.Cu")
		(net "VCC")
	)
	(segment
		(start 135.92586 105.0011)
		(end 136.01514 105.09037)
		(width 0.1524)
		(layer "F.Cu")
		(net "VCC")
	)
	(segment
		(start 129.9301 103.1971)
		(end 130.5905 102.5367)
		(width 0.508)
		(layer "F.Cu")
		(net "VCC")
	)
	(segment
		(start 135.4971 114.25783)
		(end 135.4971 108.6333)
		(width 0.508)
		(layer "F.Cu")
		(net "VCC")
	)
	(segment
		(start 148.8241 94.3411)
		(end 149.8227 94.3411)
		(width 0.2032)
		(layer "F.Cu")
		(net "VCC")
	)
	(segment
		(start 130.0393 103.6915)
		(end 131.2869 104.9391)
		(width 0.2032)
		(layer "F.Cu")
		(net "VCC")
	)
	(segment
		(start 133.87946 102.63477)
		(end 134.2069 102.96221)
		(width 0.508)
		(layer "F.Cu")
		(net "VCC")
	)
	(segment
		(start 131.5131 106.61776)
		(end 131.5131 105.11718)
		(width 0.2032)
		(layer "F.Cu")
		(net "VCC")
	)
	(segment
		(start 170.05694 100.47834)
		(end 170.1347 100.5561)
		(width 0.2032)
		(layer "F.Cu")
		(net "VCC")
	)
	(segment
		(start 135.33025 103.3274)
		(end 135.33775 103.3199)
		(width 0.508)
		(layer "F.Cu")
		(net "VCC")
	)
	(segment
		(start 130.94214 107.18872)
		(end 131.5131 106.61776)
		(width 0.2032)
		(layer "F.Cu")
		(net "VCC")
	)
	(segment
		(start 165.45674 103.2485)
		(end 168.45705 103.2485)
		(width 0.508)
		(layer "F.Cu")
		(net "VCC")
	)
	(segment
		(start 168.8187 103.4557)
		(end 168.8187 103.4137)
		(width 0.508)
		(layer "F.Cu")
		(net "VCC")
	)
	(segment
		(start 135.4971 114.25783)
		(end 140.28657 119.0473)
		(width 0.508)
		(layer "F.Cu")
		(net "VCC")
	)
	(segment
		(start 167.98714 102.58214)
		(end 168.55528 103.15028)
		(width 0.508)
		(layer "F.Cu")
		(net "VCC")
	)
	(segment
		(start 135.4971 108.6333)
		(end 135.4971 105.55216)
		(width 0.508)
		(layer "F.Cu")
		(net "VCC")
	)
	(segment
		(start 170.7745 103.4557)
		(end 170.7745 103.2533)
		(width 0.508)
		(layer "F.Cu")
		(net "VCC")
	)
	(segment
		(start 129.7591 103.5931)
		(end 129.7591 103.3681)
		(width 0.2032)
		(layer "F.Cu")
		(net "VCC")
	)
	(segment
		(start 129.7591 103.3681)
		(end 129.7591 103.2511)
		(width 0.508)
		(layer "F.Cu")
		(net "VCC")
	)
	(segment
		(start 134.2069 103.29517)
		(end 134.23914 103.3274)
		(width 0.508)
		(layer "F.Cu")
		(net "VCC")
	)
	(segment
		(start 130.32966 107.2871)
		(end 130.42804 107.18872)
		(width 0.2032)
		(layer "F.Cu")
		(net "VCC")
	)
	(segment
		(start 131.2869 104.9391)
		(end 131.33502 104.9391)
		(width 0.2032)
		(layer "F.Cu")
		(net "VCC")
	)
	(segment
		(start 156.1977 103.76076)
		(end 156.70997 103.2485)
		(width 0.508)
		(layer "F.Cu")
		(net "VCC")
	)
	(segment
		(start 167.70753 112.5961)
		(end 173.7101 112.5961)
		(width 0.508)
		(layer "F.Cu")
		(net "VCC")
	)
	(segment
		(start 161.5669 103.2485)
		(end 162.4131 104.0947)
		(width 0.508)
		(layer "F.Cu")
		(net "VCC")
	)
	(segment
		(start 149.8227 94.3411)
		(end 149.8909 94.4093)
		(width 0.2032)
		(layer "F.Cu")
		(net "VCC")
	)
	(segment
		(start 156.0301 103.9927)
		(end 156.1977 103.8251)
		(width 0.508)
		(layer "F.Cu")
		(net "VCC")
	)
	(segment
		(start 167.91894 102.58214)
		(end 167.98714 102.58214)
		(width 0.508)
		(layer "F.Cu")
		(net "VCC")
	)
	(segment
		(start 170.0839 102.5627)
		(end 170.7745 103.2533)
		(width 0.508)
		(layer "F.Cu")
		(net "VCC")
	)
	(segment
		(start 156.1977 103.8251)
		(end 156.1977 103.76076)
		(width 0.508)
		(layer "F.Cu")
		(net "VCC")
	)
	(segment
		(start 135.5225 104.7043)
		(end 135.8193 105.0011)
		(width 0.508)
		(layer "F.Cu")
		(net "VCC")
	)
	(segment
		(start 158.7612 119.0473)
		(end 161.9738 115.8347)
		(width 0.508)
		(layer "F.Cu")
		(net "VCC")
	)
	(segment
		(start 136.08894 105.3179)
		(end 136.3271 105.3179)
		(width 0.1524)
		(layer "F.Cu")
		(net "VCC")
	)
	(segment
		(start 135.5185 103.3199)
		(end 135.5225 103.3159)
		(width 0.508)
		(layer "F.Cu")
		(net "VCC")
	)
	(segment
		(start 135.4971 105.55216)
		(end 135.78776 105.2615)
		(width 0.508)
		(layer "F.Cu")
		(net "VCC")
	)
	(segment
		(start 165.15916 103.54608)
		(end 165.45674 103.2485)
		(width 0.508)
		(layer "F.Cu")
		(net "VCC")
	)
	(segment
		(start 135.33775 103.3199)
		(end 135.5185 103.3199)
		(width 0.508)
		(layer "F.Cu")
		(net "VCC")
	)
	(segment
		(start 130.42804 107.18872)
		(end 130.94214 107.18872)
		(width 0.2032)
		(layer "F.Cu")
		(net "VCC")
	)
	(segment
		(start 168.8187 103.4557)
		(end 168.8607 103.4557)
		(width 0.508)
		(layer "F.Cu")
		(net "VCC")
	)
	(segment
		(start 161.9813 92.6313)
		(end 169.82835 100.47834)
		(width 0.2032)
		(layer "F.Cu")
		(net "VCC")
	)
	(segment
		(start 135.5225 104.7043)
		(end 135.5225 103.3159)
		(width 0.508)
		(layer "F.Cu")
		(net "VCC")
	)
	(segment
		(start 129.7591 103.5931)
		(end 129.8575 103.6915)
		(width 0.2032)
		(layer "F.Cu")
		(net "VCC")
	)
	(segment
		(start 170.7785 103.4597)
		(end 170.8205 103.4597)
		(width 0.508)
		(layer "F.Cu")
		(net "VCC")
	)
	(segment
		(start 166.8835 109.8525)
		(end 168.37944 109.8525)
		(width 0.508)
		(layer "F.Cu")
		(net "VCC")
	)
	(segment
		(start 155.9841 109.2021)
		(end 155.9841 109.1921)
		(width 0.508)
		(layer "F.Cu")
		(net "VCC")
	)
	(segment
		(start 156.1977 109.67043)
		(end 156.1977 109.4157)
		(width 0.508)
		(layer "F.Cu")
		(net "VCC")
	)
	(segment
		(start 136.01514 105.2441)
		(end 136.01514 105.09037)
		(width 0.1524)
		(layer "F.Cu")
		(net "VCC")
	)
	(via
		(at 167.8995 102.5627)
		(size 0.6096)
		(drill 0.3048)
		(layers "F.Cu" "B.Cu")
		(locked yes)
		(tenting
			(front yes)
			(back no)
		)
		(net "VCC")
	)
	(via
		(at 170.0839 102.5627)
		(size 0.6096)
		(drill 0.3048)
		(layers "F.Cu" "B.Cu")
		(locked yes)
		(tenting
			(front yes)
			(back no)
		)
		(net "VCC")
	)
	(via
		(at 167.62447 109.8455)
		(size 0.6096)
		(drill 0.3048)
		(layers "F.Cu" "B.Cu")
		(locked yes)
		(tenting
			(front yes)
			(back no)
		)
		(net "VCC")
	)
	(via
		(at 165.2833 104.1629)
		(size 0.6096)
		(drill 0.3048)
		(layers "F.Cu" "B.Cu")
		(locked yes)
		(tenting
			(front yes)
			(back no)
		)
		(net "VCC")
	)
	(via
		(at 149.8909 92.6313)
		(size 0.6096)
		(drill 0.3048)
		(layers "F.Cu" "B.Cu")
		(locked yes)
		(tenting
			(front yes)
			(back no)
		)
		(net "VCC")
	)
	(via
		(at 162.4639 104.1883)
		(size 0.6096)
		(drill 0.3048)
		(layers "F.Cu" "B.Cu")
		(locked yes)
		(tenting
			(front yes)
			(back no)
		)
		(net "VCC")
	)
	(via
		(at 170.1347 100.5561)
		(size 0.6096)
		(drill 0.3048)
		(layers "F.Cu" "B.Cu")
		(locked yes)
		(tenting
			(front yes)
			(back no)
		)
		(net "VCC")
	)
	(via
		(at 167.62447 112.54053)
		(size 0.6096)
		(drill 0.3048)
		(layers "F.Cu" "B.Cu")
		(locked yes)
		(tenting
			(front yes)
			(back no)
		)
		(net "VCC")
	)
	(via
		(at 149.8909 94.4093)
		(size 0.6096)
		(drill 0.3048)
		(layers "F.Cu" "B.Cu")
		(locked yes)
		(tenting
			(front yes)
			(back no)
		)
		(net "VCC")
	)
	(segment
		(start 162.48334 104.16886)
		(end 162.72131 104.16886)
		(width 0.508)
		(layer "In1.Cu")
		(net "VCC")
	)
	(segment
		(start 162.4639 104.1883)
		(end 162.48334 104.16886)
		(width 0.508)
		(layer "In1.Cu")
		(net "VCC")
	)
	(segment
		(start 170.0839 102.5627)
		(end 170.0839 102.53521)
		(width 0.508)
		(layer "In1.Cu")
		(net "VCC")
	)
	(segment
		(start 170.1347 102.48441)
		(end 170.1347 100.5561)
		(width 0.508)
		(layer "In1.Cu")
		(net "VCC")
	)
	(segment
		(start 162.72131 104.16886)
		(end 162.72727 104.1629)
		(width 0.508)
		(layer "In1.Cu")
		(net "VCC")
	)
	(segment
		(start 170.0839 102.53521)
		(end 170.1347 102.48441)
		(width 0.508)
		(layer "In1.Cu")
		(net "VCC")
	)
	(segment
		(start 162.72727 104.1629)
		(end 165.2833 104.1629)
		(width 0.508)
		(layer "In1.Cu")
		(net "VCC")
	)
	(segment
		(start 167.62447 112.54053)
		(end 167.62447 109.8455)
		(width 0.508)
		(layer "In1.Cu")
		(net "VCC")
	)
	(segment
		(start 167.8995 102.5627)
		(end 170.0839 102.5627)
		(width 0.508)
		(layer "In1.Cu")
		(net "VCC")
	)
	(segment
		(start 149.8909 94.4093)
		(end 149.8909 92.6313)
		(width 0.2032)
		(layer "In1.Cu")
		(net "VCC")
	)
	(segment
		(start 169.7537 115.8347)
		(end 172.3313 115.8347)
		(width 0.508)
		(layer "F.Cu")
		(net "VCC_ANT")
	)
	(segment
		(start 174.5035 113.6625)
		(end 175.3417 113.6625)
		(width 0.508)
		(layer "F.Cu")
		(net "VCC_ANT")
	)
	(segment
		(start 172.3313 115.8347)
		(end 174.5035 113.6625)
		(width 0.508)
		(layer "F.Cu")
		(net "VCC_ANT")
	)
	(segment
		(start 176.19649 112.80772)
		(end 178.04848 112.80772)
		(width 0.508)
		(layer "F.Cu")
		(net "VCC_ANT")
	)
	(segment
		(start 130.9781 114.1291)
		(end 131.02864 114.17964)
		(width 0.508)
		(layer "F.Cu")
		(net "VCC_ANT")
	)
	(segment
		(start 178.04848 112.80772)
		(end 178.2601 112.5961)
		(width 0.508)
		(layer "F.Cu")
		(net "VCC_ANT")
	)
	(segment
		(start 131.02864 116.25835)
		(end 131.02864 114.17964)
		(width 0.508)
		(layer "F.Cu")
		(net "VCC_ANT")
	)
	(segment
		(start 131.02864 116.54264)
		(end 134.4477 119.9617)
		(width 0.508)
		(layer "F.Cu")
		(net "VCC_ANT")
	)
	(segment
		(start 170.5601 118.05304)
		(end 170.5601 116.6411)
		(width 0.508)
		(layer "F.Cu")
		(net "VCC_ANT")
	)
	(segment
		(start 175.3417 113.6625)
		(end 176.19649 112.80772)
		(width 0.508)
		(layer "F.Cu")
		(net "VCC_ANT")
	)
	(segment
		(start 169.7537 115.8347)
		(end 170.5601 116.6411)
		(width 0.508)
		(layer "F.Cu")
		(net "VCC_ANT")
	)
	(segment
		(start 134.4477 119.9617)
		(end 168.65144 119.9617)
		(width 0.508)
		(layer "F.Cu")
		(net "VCC_ANT")
	)
	(segment
		(start 168.65144 119.9617)
		(end 170.5601 118.05304)
		(width 0.508)
		(layer "F.Cu")
		(net "VCC_ANT")
	)
	(segment
		(start 131.02864 116.54264)
		(end 131.02864 116.25835)
		(width 0.508)
		(layer "F.Cu")
		(net "VCC_ANT")
	)
	(segment
		(start 167.23024 105.9983)
		(end 168.47257 107.24063)
		(width 0.2032)
		(layer "F.Cu")
		(net "TXD")
	)
	(segment
		(start 165.89129 105.9983)
		(end 167.23024 105.9983)
		(width 0.2032)
		(layer "F.Cu")
		(net "TXD")
	)
	(segment
		(start 165.7135 106.3063)
		(end 165.7135 106.17609)
		(width 0.2032)
		(layer "F.Cu")
		(net "TXD")
	)
	(segment
		(start 156.58952 97.2441)
		(end 165.5215 106.17609)
		(width 0.2032)
		(layer "F.Cu")
		(net "TXD")
	)
	(segment
		(start 153.30811 97.0699)
		(end 153.60651 96.7715)
		(width 0.2032)
		(layer "F.Cu")
		(net "TXD")
	)
	(segment
		(start 165.5215 106.3063)
		(end 165.5215 106.17609)
		(width 0.2032)
		(layer "F.Cu")
		(net "TXD")
	)
	(segment
		(start 168.6615 107.42956)
		(end 168.6615 107.37527)
		(width 0.2032)
		(layer "F.Cu")
		(net "TXD")
	)
	(segment
		(start 165.5215 106.3063)
		(end 165.6175 106.4023)
		(width 0.2032)
		(layer "F.Cu")
		(net "TXD")
	)
	(segment
		(start 165.6175 106.6523)
		(end 165.6175 106.4023)
		(width 0.2032)
		(layer "F.Cu")
		(net "TXD")
	)
	(segment
		(start 153.30811 97.2441)
		(end 153.30811 97.0699)
		(width 0.2032)
		(layer "F.Cu")
		(net "TXD")
	)
	(segment
		(start 153.30811 97.2441)
		(end 156.58952 97.2441)
		(width 0.2032)
		(layer "F.Cu")
		(net "TXD")
	)
	(segment
		(start 168.47257 107.24063)
		(end 168.52686 107.24063)
		(width 0.2032)
		(layer "F.Cu")
		(net "TXD")
	)
	(segment
		(start 165.6175 106.4023)
		(end 165.7135 106.3063)
		(width 0.2032)
		(layer "F.Cu")
		(net "TXD")
	)
	(segment
		(start 168.52686 107.24063)
		(end 168.6615 107.37527)
		(width 0.2032)
		(layer "F.Cu")
		(net "TXD")
	)
	(segment
		(start 165.7135 106.17609)
		(end 165.89129 105.9983)
		(width 0.2032)
		(layer "F.Cu")
		(net "TXD")
	)
	(segment
		(start 165.2135 110.32852)
		(end 166.31229 111.4273)
		(width 0.2032)
		(layer "F.Cu")
		(net "TXD_OUT")
	)
	(segment
		(start 165.2135 109.43487)
		(end 165.2135 109.37609)
		(width 0.2032)
		(layer "F.Cu")
		(net "TXD_OUT")
	)
	(segment
		(start 165.1175 109.8523)
		(end 165.1659 109.8039)
		(width 0.2032)
		(layer "F.Cu")
		(net "TXD_OUT")
	)
	(segment
		(start 165.2135 109.37609)
		(end 166.42895 108.16064)
		(width 0.2032)
		(layer "F.Cu")
		(net "TXD_OUT")
	)
	(segment
		(start 175.22311 111.4273)
		(end 176.05431 110.5961)
		(width 0.2032)
		(layer "F.Cu")
		(net "TXD_OUT")
	)
	(segment
		(start 165.1659 109.8039)
		(end 165.1659 109.48247)
		(width 0.2032)
		(layer "F.Cu")
		(net "TXD_OUT")
	)
	(segment
		(start 166.31229 111.4273)
		(end 175.22311 111.4273)
		(width 0.2032)
		(layer "F.Cu")
		(net "TXD_OUT")
	)
	(segment
		(start 169.15174 107.8253)
		(end 169.15174 107.03382)
		(width 0.2032)
		(layer "F.Cu")
		(net "TXD_OUT")
	)
	(segment
		(start 166.42895 108.16064)
		(end 168.6615 108.16064)
		(width 0.2032)
		(layer "F.Cu")
		(net "TXD_OUT")
	)
	(segment
		(start 169.00295 107.97409)
		(end 169.15174 107.8253)
		(width 0.2032)
		(layer "F.Cu")
		(net "TXD_OUT")
	)
	(segment
		(start 168.6615 108.16064)
		(end 168.6615 108.10873)
		(width 0.2032)
		(layer "F.Cu")
		(net "TXD_OUT")
	)
	(segment
		(start 168.6615 108.10873)
		(end 168.79614 107.97409)
		(width 0.2032)
		(layer "F.Cu")
		(net "TXD_OUT")
	)
	(segment
		(start 168.79614 107.97409)
		(end 169.00295 107.97409)
		(width 0.2032)
		(layer "F.Cu")
		(net "TXD_OUT")
	)
	(segment
		(start 165.1175 110.1023)
		(end 165.1175 109.8523)
		(width 0.2032)
		(layer "F.Cu")
		(net "TXD_OUT")
	)
	(segment
		(start 165.1175 110.1023)
		(end 165.2135 110.1983)
		(width 0.2032)
		(layer "F.Cu")
		(net "TXD_OUT")
	)
	(segment
		(start 168.8647 106.74679)
		(end 168.8647 104.4597)
		(width 0.2032)
		(layer "F.Cu")
		(net "TXD_OUT")
	)
	(segment
		(start 176.05431 110.5961)
		(end 178.2601 110.5961)
		(width 0.2032)
		(layer "F.Cu")
		(net "TXD_OUT")
	)
	(segment
		(start 165.2135 110.32852)
		(end 165.2135 110.1983)
		(width 0.2032)
		(layer "F.Cu")
		(net "TXD_OUT")
	)
	(segment
		(start 165.1659 109.48247)
		(end 165.2135 109.43487)
		(width 0.2032)
		(layer "F.Cu")
		(net "TXD_OUT")
	)
	(segment
		(start 168.8647 106.74679)
		(end 169.15174 107.03382)
		(width 0.2032)
		(layer "F.Cu")
		(net "TXD_OUT")
	)
	(segment
		(start 177.56433 106.1877)
		(end 177.97273 106.5961)
		(width 0.2032)
		(layer "F.Cu")
		(net "TP2")
	)
	(segment
		(start 162.5147 92.0725)
		(end 171.5317 101.0895)
		(width 0.2032)
		(layer "F.Cu")
		(net "TP2")
	)
	(segment
		(start 177.97273 106.5961)
		(end 178.2601 106.5961)
		(width 0.2032)
		(layer "F.Cu")
		(net "TP2")
	)
	(segment
		(start 140.10811 97.2441)
		(end 140.10811 95.12988)
		(width 0.2032)
		(layer "F.Cu")
		(net "TP2")
	)
	(segment
		(start 177.56433 106.1877)
		(end 177.56433 105.90033)
		(width 0.2032)
		(layer "F.Cu")
		(net "TP2")
	)
	(segment
		(start 140.10811 95.12988)
		(end 143.16549 92.0725)
		(width 0.2032)
		(layer "F.Cu")
		(net "TP2")
	)
	(segment
		(start 178.2601 106.5961)
		(end 178.2601 101.1245)
		(width 0.2032)
		(layer "F.Cu")
		(net "TP2")
	)
	(segment
		(start 172.7535 101.0895)
		(end 177.56433 105.90033)
		(width 0.2032)
		(layer "F.Cu")
		(net "TP2")
	)
	(segment
		(start 178.1865 101.0509)
		(end 178.2601 101.1245)
		(width 0.2032)
		(layer "F.Cu")
		(net "TP2")
	)
	(segment
		(start 143.16549 92.0725)
		(end 162.5147 92.0725)
		(width 0.2032)
		(layer "F.Cu")
		(net "TP2")
	)
	(segment
		(start 171.5317 101.0895)
		(end 172.7535 101.0895)
		(width 0.2032)
		(layer "F.Cu")
		(net "TP2")
	)
	(segment
		(start 140.9581 95.40741)
		(end 140.9581 94.78278)
		(width 0.2032)
		(layer "F.Cu")
		(net "TP1")
	)
	(segment
		(start 173.07852 108.5961)
		(end 173.7101 108.5961)
		(width 0.2032)
		(layer "F.Cu")
		(net "TP1")
	)
	(segment
		(start 140.9581 95.40741)
		(end 141.20811 95.65742)
		(width 0.2032)
		(layer "F.Cu")
		(net "TP1")
	)
	(segment
		(start 172.67012 108.1877)
		(end 173.07852 108.5961)
		(width 0.2032)
		(layer "F.Cu")
		(net "TP1")
	)
	(segment
		(start 171.3745 106.60471)
		(end 172.67012 107.90033)
		(width 0.2032)
		(layer "F.Cu")
		(net "TP1")
	)
	(segment
		(start 170.3125 101.6991)
		(end 171.3745 102.7611)
		(width 0.2032)
		(layer "F.Cu")
		(net "TP1")
	)
	(segment
		(start 152.04942 94.0791)
		(end 161.2701 94.0791)
		(width 0.2032)
		(layer "F.Cu")
		(net "TP1")
	)
	(segment
		(start 151.79742 93.8271)
		(end 152.04942 94.0791)
		(width 0.2032)
		(layer "F.Cu")
		(net "TP1")
	)
	(segment
		(start 141.20811 97.2441)
		(end 141.20811 95.65742)
		(width 0.2032)
		(layer "F.Cu")
		(net "TP1")
	)
	(segment
		(start 141.39979 94.3411)
		(end 146.3709 94.3411)
		(width 0.2032)
		(layer "F.Cu")
		(net "TP1")
	)
	(segment
		(start 168.8901 101.6991)
		(end 170.3125 101.6991)
		(width 0.2032)
		(layer "F.Cu")
		(net "TP1")
	)
	(segment
		(start 171.3745 106.60471)
		(end 171.3745 102.7611)
		(width 0.2032)
		(layer "F.Cu")
		(net "TP1")
	)
	(segment
		(start 140.9581 94.78278)
		(end 141.39979 94.3411)
		(width 0.2032)
		(layer "F.Cu")
		(net "TP1")
	)
	(segment
		(start 146.88489 93.8271)
		(end 151.79742 93.8271)
		(width 0.2032)
		(layer "F.Cu")
		(net "TP1")
	)
	(segment
		(start 146.3709 94.3411)
		(end 146.88489 93.8271)
		(width 0.2032)
		(layer "F.Cu")
		(net "TP1")
	)
	(segment
		(start 172.67012 108.1877)
		(end 172.67012 107.90033)
		(width 0.2032)
		(layer "F.Cu")
		(net "TP1")
	)
	(segment
		(start 161.2701 94.0791)
		(end 168.8901 101.6991)
		(width 0.2032)
		(layer "F.Cu")
		(net "TP1")
	)
	(segment
		(start 170.60966 107.61611)
		(end 170.7443 107.48147)
		(width 0.2032)
		(layer "F.Cu")
		(net "RXD")
	)
	(segment
		(start 152.3547 97.0975)
		(end 152.3547 96.27732)
		(width 0.2032)
		(layer "F.Cu")
		(net "RXD")
	)
	(segment
		(start 152.74952 95.8825)
		(end 161.9559 95.8825)
		(width 0.2032)
		(layer "F.Cu")
		(net "RXD")
	)
	(segment
		(start 161.9559 95.8825)
		(end 168.0773 102.0039)
		(width 0.2032)
		(layer "F.Cu")
		(net "RXD")
	)
	(segment
		(start 170.67688 104.31607)
		(end 170.8205 104.4597)
		(width 0.2032)
		(layer "F.Cu")
		(net "RXD")
	)
	(segment
		(start 170.38948 104.31607)
		(end 170.67688 104.31607)
		(width 0.2032)
		(layer "F.Cu")
		(net "RXD")
	)
	(segment
		(start 166.1175 109.8523)
		(end 166.1659 109.9007)
		(width 0.2032)
		(layer "F.Cu")
		(net "RXD")
	)
	(segment
		(start 170.40285 107.61611)
		(end 170.60966 107.61611)
		(width 0.2032)
		(layer "F.Cu")
		(net "RXD")
	)
	(segment
		(start 152.3547 96.27732)
		(end 152.74952 95.8825)
		(width 0.2032)
		(layer "F.Cu")
		(net "RXD")
	)
	(segment
		(start 170.8205 107.35336)
		(end 170.8205 104.4597)
		(width 0.2032)
		(layer "F.Cu")
		(net "RXD")
	)
	(segment
		(start 168.31811 102.0039)
		(end 169.4187 103.10449)
		(width 0.2032)
		(layer "F.Cu")
		(net "RXD")
	)
	(segment
		(start 168.0773 102.0039)
		(end 168.31811 102.0039)
		(width 0.2032)
		(layer "F.Cu")
		(net "RXD")
	)
	(segment
		(start 170.25406 110.49514)
		(end 170.25406 107.7649)
		(width 0.2032)
		(layer "F.Cu")
		(net "RXD")
	)
	(segment
		(start 166.88048 110.9955)
		(end 169.7537 110.9955)
		(width 0.2032)
		(layer "F.Cu")
		(net "RXD")
	)
	(segment
		(start 169.4187 103.3453)
		(end 169.4187 103.10449)
		(width 0.2032)
		(layer "F.Cu")
		(net "RXD")
	)
	(segment
		(start 170.7443 107.42956)
		(end 170.8205 107.35336)
		(width 0.2032)
		(layer "F.Cu")
		(net "RXD")
	)
	(segment
		(start 166.1659 110.28092)
		(end 166.1659 109.9007)
		(width 0.2032)
		(layer "F.Cu")
		(net "RXD")
	)
	(segment
		(start 152.20811 97.2441)
		(end 152.3547 97.0975)
		(width 0.2032)
		(layer "F.Cu")
		(net "RXD")
	)
	(segment
		(start 169.7537 110.9955)
		(end 170.25406 110.49514)
		(width 0.2032)
		(layer "F.Cu")
		(net "RXD")
	)
	(segment
		(start 166.1659 110.28092)
		(end 166.88048 110.9955)
		(width 0.2032)
		(layer "F.Cu")
		(net "RXD")
	)
	(segment
		(start 169.4187 103.3453)
		(end 170.38948 104.31607)
		(width 0.2032)
		(layer "F.Cu")
		(net "RXD")
	)
	(segment
		(start 170.7443 107.48147)
		(end 170.7443 107.42956)
		(width 0.2032)
		(layer "F.Cu")
		(net "RXD")
	)
	(segment
		(start 170.25406 107.7649)
		(end 170.40285 107.61611)
		(width 0.2032)
		(layer "F.Cu")
		(net "RXD")
	)
	(segment
		(start 170.93323 108.34957)
		(end 171.94377 109.3601)
		(width 0.2032)
		(layer "F.Cu")
		(net "RXD_IN")
	)
	(segment
		(start 166.5215 107.06973)
		(end 166.5691 107.02213)
		(width 0.2032)
		(layer "F.Cu")
		(net "RXD_IN")
	)
	(segment
		(start 170.7443 108.21493)
		(end 170.7443 108.16064)
		(width 0.2032)
		(layer "F.Cu")
		(net "RXD_IN")
	)
	(segment
		(start 175.29031 109.3601)
		(end 176.05431 108.5961)
		(width 0.2032)
		(layer "F.Cu")
		(net "RXD_IN")
	)
	(segment
		(start 164.6991 108.95092)
		(end 166.5215 107.12851)
		(width 0.2032)
		(layer "F.Cu")
		(net "RXD_IN")
	)
	(segment
		(start 179.84031 109.8321)
		(end 179.84031 109.8321)
		(width 0.2032)
		(layer "F.Cu")
		(net "RXD_IN")
	)
	(segment
		(start 178.89168 108.5961)
		(end 179.30008 109.0045)
		(width 0.2032)
		(layer "F.Cu")
		(net "RXD_IN")
	)
	(segment
		(start 166.5691 107.02213)
		(end 166.5691 106.7007)
		(width 0.2032)
		(layer "F.Cu")
		(net "RXD_IN")
	)
	(segment
		(start 166.6175 106.87673)
		(end 166.6175 106.6523)
		(width 0.2032)
		(layer "F.Cu")
		(net "RXD_IN")
	)
	(segment
		(start 178.2601 108.5961)
		(end 178.89168 108.5961)
		(width 0.2032)
		(layer "F.Cu")
		(net "RXD_IN")
	)
	(segment
		(start 166.5215 107.12851)
		(end 166.5215 107.06973)
		(width 0.2032)
		(layer "F.Cu")
		(net "RXD_IN")
	)
	(segment
		(start 179.30008 109.29187)
		(end 179.30008 109.0045)
		(width 0.2032)
		(layer "F.Cu")
		(net "RXD_IN")
	)
	(segment
		(start 179.84031 109.8321)
		(end 179.9891 109.98089)
		(width 0.2032)
		(layer "F.Cu")
		(net "RXD_IN")
	)
	(segment
		(start 179.9891 111.21131)
		(end 179.9891 109.98089)
		(width 0.2032)
		(layer "F.Cu")
		(net "RXD_IN")
	)
	(segment
		(start 166.0453 111.8083)
		(end 179.39211 111.8083)
		(width 0.2032)
		(layer "F.Cu")
		(net "RXD_IN")
	)
	(segment
		(start 166.5691 106.7007)
		(end 166.6175 106.6523)
		(width 0.2032)
		(layer "F.Cu")
		(net "RXD_IN")
	)
	(segment
		(start 176.05431 108.5961)
		(end 178.2601 108.5961)
		(width 0.2032)
		(layer "F.Cu")
		(net "RXD_IN")
	)
	(segment
		(start 170.87894 108.34957)
		(end 170.93323 108.34957)
		(width 0.2032)
		(layer "F.Cu")
		(net "RXD_IN")
	)
	(segment
		(start 164.6991 110.4621)
		(end 164.6991 108.95092)
		(width 0.2032)
		(layer "F.Cu")
		(net "RXD_IN")
	)
	(segment
		(start 171.94377 109.3601)
		(end 175.29031 109.3601)
		(width 0.2032)
		(layer "F.Cu")
		(net "RXD_IN")
	)
	(segment
		(start 164.6991 110.4621)
		(end 166.0453 111.8083)
		(width 0.2032)
		(layer "F.Cu")
		(net "RXD_IN")
	)
	(segment
		(start 170.7443 108.21493)
		(end 170.87894 108.34957)
		(width 0.2032)
		(layer "F.Cu")
		(net "RXD_IN")
	)
	(segment
		(start 179.39211 111.8083)
		(end 179.9891 111.21131)
		(width 0.2032)
		(layer "F.Cu")
		(net "RXD_IN")
	)
	(segment
		(start 179.30008 109.29187)
		(end 179.84031 109.8321)
		(width 0.2032)
		(layer "F.Cu")
		(net "RXD_IN")
	)
	(segment
		(start 170.8822 101.6389)
		(end 171.3191 101.6389)
		(width 0.2032)
		(layer "F.Cu")
		(net "RST")
	)
	(segment
		(start 172.0905 105.3313)
		(end 172.0905 102.4103)
		(width 0.2032)
		(layer "F.Cu")
		(net "RST")
	)
	(segment
		(start 171.3191 101.6389)
		(end 172.0905 102.4103)
		(width 0.2032)
		(layer "F.Cu")
		(net "RST")
	)
	(segment
		(start 171.3355 110.5961)
		(end 173.7101 110.5961)
		(width 0.2032)
		(layer "F.Cu")
		(net "RST")
	)
	(segment
		(start 169.3981 101.1149)
		(end 170.3582 101.1149)
		(width 0.2032)
		(layer "F.Cu")
		(net "RST")
	)
	(segment
		(start 145.6999 97.1523)
		(end 145.6999 94.8999)
		(width 0.2032)
		(layer "F.Cu")
		(net "RST")
	)
	(segment
		(start 170.3582 101.1149)
		(end 170.8822 101.6389)
		(width 0.2032)
		(layer "F.Cu")
		(net "RST")
	)
	(segment
		(start 146.6397 93.3171)
		(end 161.6003 93.3171)
		(width 0.2032)
		(layer "F.Cu")
		(net "RST")
	)
	(segment
		(start 145.60811 97.2441)
		(end 145.6999 97.1523)
		(width 0.2032)
		(layer "F.Cu")
		(net "RST")
	)
	(segment
		(start 161.6003 93.3171)
		(end 169.3981 101.1149)
		(width 0.2032)
		(layer "F.Cu")
		(net "RST")
	)
	(segment
		(start 146.1825 93.7743)
		(end 146.6397 93.3171)
		(width 0.2032)
		(layer "F.Cu")
		(net "RST")
	)
	(segment
		(start 171.3285 110.5891)
		(end 171.3355 110.5961)
		(width 0.2032)
		(layer "F.Cu")
		(net "RST")
	)
	(segment
		(start 145.6999 93.7743)
		(end 146.1825 93.7743)
		(width 0.2032)
		(layer "F.Cu")
		(net "RST")
	)
	(via
		(at 145.6999 93.7743)
		(size 0.6096)
		(drill 0.3048)
		(layers "F.Cu" "B.Cu")
		(locked yes)
		(tenting
			(front yes)
			(back no)
		)
		(net "RST")
	)
	(via
		(at 172.0905 105.3313)
		(size 0.6096)
		(drill 0.3048)
		(layers "F.Cu" "B.Cu")
		(locked yes)
		(tenting
			(front yes)
			(back no)
		)
		(net "RST")
	)
	(via
		(at 145.6999 94.8999)
		(size 0.6096)
		(drill 0.3048)
		(layers "F.Cu" "B.Cu")
		(locked yes)
		(tenting
			(front yes)
			(back no)
		)
		(net "RST")
	)
	(via
		(at 171.3285 110.5891)
		(size 0.6096)
		(drill 0.3048)
		(layers "F.Cu" "B.Cu")
		(locked yes)
		(tenting
			(front yes)
			(back no)
		)
		(net "RST")
	)
	(segment
		(start 171.3285 110.5891)
		(end 172.0905 109.8271)
		(width 0.2032)
		(layer "In1.Cu")
		(net "RST")
	)
	(segment
		(start 172.0905 109.8271)
		(end 172.0905 105.3313)
		(width 0.2032)
		(layer "In1.Cu")
		(net "RST")
	)
	(segment
		(start 145.6999 94.8999)
		(end 145.6999 93.7743)
		(width 0.2032)
		(layer "In1.Cu")
		(net "RST")
	)
	(segment
		(start 134.77466 101.1657)
		(end 139.23651 101.1657)
		(width 0.1778)
		(layer "F.Cu")
		(net "RF_IN")
	)
	(segment
		(start 139.23651 101.1657)
		(end 139.25811 101.1441)
		(width 0.1778)
		(layer "F.Cu")
		(net "RF_IN")
	)
	(segment
		(start 144.9541 117.99931)
		(end 144.9541 117.99931)
		(width 0.2032)
		(layer "F.Cu")
		(net "NetTP8_1")
	)
	(segment
		(start 144.80651 117.85171)
		(end 144.9541 117.99931)
		(width 0.2032)
		(layer "F.Cu")
		(net "NetTP8_1")
	)
	(segment
		(start 144.9541 117.99931)
		(end 145.4585 118.5037)
		(width 0.2032)
		(layer "F.Cu")
		(net "NetTP8_1")
	)
	(segment
		(start 145.4585 118.5037)
		(end 157.8005 118.5037)
		(width 0.2032)
		(layer "F.Cu")
		(net "NetTP8_1")
	)
	(segment
		(start 144.50811 117.1441)
		(end 144.80651 117.4425)
		(width 0.2032)
		(layer "F.Cu")
		(net "NetTP8_1")
	)
	(segment
		(start 157.8005 118.5037)
		(end 159.2381 117.0661)
		(width 0.2032)
		(layer "F.Cu")
		(net "NetTP8_1")
	)
	(segment
		(start 144.80651 117.85171)
		(end 144.80651 117.4425)
		(width 0.2032)
		(layer "F.Cu")
		(net "NetTP8_1")
	)
	(segment
		(start 156.42842 118.1481)
		(end 157.35796 117.21856)
		(width 0.2032)
		(layer "F.Cu")
		(net "NetTP7_1")
	)
	(segment
		(start 152.62554 118.1481)
		(end 156.42842 118.1481)
		(width 0.2032)
		(layer "F.Cu")
		(net "NetTP7_1")
	)
	(segment
		(start 152.50651 118.02907)
		(end 152.50651 117.4425)
		(width 0.2032)
		(layer "F.Cu")
		(net "NetTP7_1")
	)
	(segment
		(start 157.35796 117.21856)
		(end 157.68864 117.21856)
		(width 0.2032)
		(layer "F.Cu")
		(net "NetTP7_1")
	)
	(segment
		(start 157.68864 117.21856)
		(end 157.8411 117.0661)
		(width 0.2032)
		(layer "F.Cu")
		(net "NetTP7_1")
	)
	(segment
		(start 152.50651 118.02907)
		(end 152.62554 118.1481)
		(width 0.2032)
		(layer "F.Cu")
		(net "NetTP7_1")
	)
	(segment
		(start 152.20811 117.1441)
		(end 152.50651 117.4425)
		(width 0.2032)
		(layer "F.Cu")
		(net "NetTP7_1")
	)
	(segment
		(start 156.3661 117.1441)
		(end 156.4441 117.0661)
		(width 0.2032)
		(layer "F.Cu")
		(net "NetTP6_1")
	)
	(segment
		(start 153.30811 117.1441)
		(end 156.3661 117.1441)
		(width 0.2032)
		(layer "F.Cu")
		(net "NetTP6_1")
	)
	(segment
		(start 150.00811 97.2441)
		(end 150.00811 95.6891)
		(width 0.2032)
		(layer "F.Cu")
		(net "NetTP5_1")
	)
	(segment
		(start 150.00811 95.6891)
		(end 150.6021 95.0951)
		(width 0.2032)
		(layer "F.Cu")
		(net "NetTP5_1")
	)
	(segment
		(start 151.10811 97.2441)
		(end 151.10811 95.9861)
		(width 0.2032)
		(layer "F.Cu")
		(net "NetTP4_1")
	)
	(segment
		(start 151.10811 95.9861)
		(end 151.9991 95.0951)
		(width 0.2032)
		(layer "F.Cu")
		(net "NetTP4_1")
	)
	(segment
		(start 141.7121 95.0951)
		(end 142.30811 95.6911)
		(width 0.2032)
		(layer "F.Cu")
		(net "NetTP3_1")
	)
	(segment
		(start 142.30811 97.2441)
		(end 142.30811 95.6911)
		(width 0.2032)
		(layer "F.Cu")
		(net "NetTP3_1")
	)
	(segment
		(start 143.1091 95.31071)
		(end 143.1091 95.0951)
		(width 0.2032)
		(layer "F.Cu")
		(net "NetTP2_1")
	)
	(segment
		(start 143.1091 95.31071)
		(end 143.40811 95.60972)
		(width 0.2032)
		(layer "F.Cu")
		(net "NetTP2_1")
	)
	(segment
		(start 143.40811 97.2441)
		(end 143.40811 95.60972)
		(width 0.2032)
		(layer "F.Cu")
		(net "NetTP2_1")
	)
	(segment
		(start 144.50811 97.2441)
		(end 144.50811 95.0971)
		(width 0.2032)
		(layer "F.Cu")
		(net "NetTP1_1")
	)
	(segment
		(start 144.5061 95.0951)
		(end 144.50811 95.0971)
		(width 0.2032)
		(layer "F.Cu")
		(net "NetTP1_1")
	)
	(segment
		(start 131.0361 107.82769)
		(end 131.51033 107.35346)
		(width 0.2032)
		(layer "F.Cu")
		(net "NetR10_1")
	)
	(segment
		(start 130.97271 106.25792)
		(end 130.97271 105.70449)
		(width 0.2032)
		(layer "F.Cu")
		(net "NetR10_1")
	)
	(segment
		(start 130.8663 106.36433)
		(end 130.97271 106.25792)
		(width 0.2032)
		(layer "F.Cu")
		(net "NetR10_1")
	)
	(segment
		(start 130.8663 106.4743)
		(end 130.8663 106.36433)
		(width 0.2032)
		(layer "F.Cu")
		(net "NetR10_1")
	)
	(segment
		(start 130.97271 105.70449)
		(end 131.0591 105.6181)
		(width 0.2032)
		(layer "F.Cu")
		(net "NetR10_1")
	)
	(segment
		(start 131.0361 109.1921)
		(end 132.07557 109.1921)
		(width 0.508)
		(layer "F.Cu")
		(net "NetR10_1")
	)
	(segment
		(start 131.0361 109.1921)
		(end 131.0361 107.82769)
		(width 0.2032)
		(layer "F.Cu")
		(net "NetR10_1")
	)
	(via
		(at 131.56766 107.35346)
		(size 0.6096)
		(drill 0.3048)
		(layers "F.Cu" "B.Cu")
		(locked yes)
		(tenting
			(front yes)
			(back no)
		)
		(net "NetR10_1")
	)
	(via
		(at 130.8663 106.4743)
		(size 0.6096)
		(drill 0.3048)
		(layers "F.Cu" "B.Cu")
		(locked yes)
		(tenting
			(front yes)
			(back no)
		)
		(net "NetR10_1")
	)
	(segment
		(start 131.4899 107.2757)
		(end 131.56766 107.35346)
		(width 0.2032)
		(layer "In1.Cu")
		(net "NetR10_1")
	)
	(segment
		(start 130.8663 106.4743)
		(end 131.4899 107.0979)
		(width 0.2032)
		(layer "In1.Cu")
		(net "NetR10_1")
	)
	(segment
		(start 131.4899 107.2757)
		(end 131.4899 107.0979)
		(width 0.2032)
		(layer "In1.Cu")
		(net "NetR10_1")
	)
	(segment
		(start 130.0281 112.1291)
		(end 130.0281 109.2421)
		(width 0.508)
		(layer "F.Cu")
		(net "NetQ1_3")
	)
	(segment
		(start 130.0281 109.2421)
		(end 130.0361 109.2341)
		(width 0.508)
		(layer "F.Cu")
		(net "NetQ1_3")
	)
	(segment
		(start 127.9961 109.2301)
		(end 128.0341 109.1921)
		(width 0.508)
		(layer "F.Cu")
		(net "NetQ1_3")
	)
	(segment
		(start 128.0341 109.1921)
		(end 130.0361 109.1921)
		(width 0.508)
		(layer "F.Cu")
		(net "NetQ1_3")
	)
	(segment
		(start 130.0361 109.2341)
		(end 130.0361 109.1921)
		(width 0.508)
		(layer "F.Cu")
		(net "NetQ1_3")
	)
	(segment
		(start 130.17772 113.73429)
		(end 130.17772 113.72027)
		(width 0.2032)
		(layer "F.Cu")
		(net "NetQ1_1")
	)
	(segment
		(start 129.0781 114.1291)
		(end 129.7829 114.1291)
		(width 0.2032)
		(layer "F.Cu")
		(net "NetQ1_1")
	)
	(segment
		(start 133.5825 105.9139)
		(end 133.60332 105.9139)
		(width 0.2032)
		(layer "F.Cu")
		(net "NetQ1_1")
	)
	(segment
		(start 133.1271 105.8179)
		(end 133.1755 105.8663)
		(width 0.2032)
		(layer "F.Cu")
		(net "NetQ1_1")
	)
	(segment
		(start 130.2788 116.25835)
		(end 130.29757 116.25835)
		(width 0.508)
		(layer "F.Cu")
		(net "NetQ1_1")
	)
	(segment
		(start 129.07902 115.03981)
		(end 130.24327 116.20406)
		(width 0.508)
		(layer "F.Cu")
		(net "NetQ1_1")
	)
	(segment
		(start 133.7811 112.16001)
		(end 133.7811 106.09169)
		(width 0.2032)
		(layer "F.Cu")
		(net "NetQ1_1")
	)
	(segment
		(start 133.5349 105.8663)
		(end 133.5825 105.9139)
		(width 0.2032)
		(layer "F.Cu")
		(net "NetQ1_1")
	)
	(segment
		(start 129.07902 115.03981)
		(end 129.07902 114.13002)
		(width 0.508)
		(layer "F.Cu")
		(net "NetQ1_1")
	)
	(segment
		(start 133.60332 105.9139)
		(end 133.7811 106.09169)
		(width 0.2032)
		(layer "F.Cu")
		(net "NetQ1_1")
	)
	(segment
		(start 130.24327 116.22283)
		(end 130.24327 116.20406)
		(width 0.508)
		(layer "F.Cu")
		(net "NetQ1_1")
	)
	(segment
		(start 130.17772 113.72027)
		(end 130.57253 113.32546)
		(width 0.2032)
		(layer "F.Cu")
		(net "NetQ1_1")
	)
	(segment
		(start 129.0781 114.1291)
		(end 129.07902 114.13002)
		(width 0.508)
		(layer "F.Cu")
		(net "NetQ1_1")
	)
	(segment
		(start 130.24327 116.22283)
		(end 130.2788 116.25835)
		(width 0.508)
		(layer "F.Cu")
		(net "NetQ1_1")
	)
	(segment
		(start 133.1755 105.8663)
		(end 133.5349 105.8663)
		(width 0.2032)
		(layer "F.Cu")
		(net "NetQ1_1")
	)
	(segment
		(start 129.7829 114.1291)
		(end 130.17772 113.73429)
		(width 0.2032)
		(layer "F.Cu")
		(net "NetQ1_1")
	)
	(segment
		(start 132.61565 113.32546)
		(end 133.7811 112.16001)
		(width 0.2032)
		(layer "F.Cu")
		(net "NetQ1_1")
	)
	(segment
		(start 130.57253 113.32546)
		(end 132.61565 113.32546)
		(width 0.2032)
		(layer "F.Cu")
		(net "NetQ1_1")
	)
	(segment
		(start 169.31923 117.91917)
		(end 169.7537 117.4847)
		(width 0.508)
		(layer "F.Cu")
		(net "NetDS3_K")
	)
	(segment
		(start 167.7807 117.91917)
		(end 169.31923 117.91917)
		(width 0.508)
		(layer "F.Cu")
		(net "NetDS3_K")
	)
	(segment
		(start 165.32323 117.91917)
		(end 165.7577 117.4847)
		(width 0.508)
		(layer "F.Cu")
		(net "NetDS2_K")
	)
	(segment
		(start 163.7847 117.91917)
		(end 165.32323 117.91917)
		(width 0.508)
		(layer "F.Cu")
		(net "NetDS2_K")
	)
	(segment
		(start 131.0591 103.57988)
		(end 131.1575 103.67828)
		(width 0.2032)
		(layer "F.Cu")
		(net "NetC10_1")
	)
	(segment
		(start 132.32584 106.13043)
		(end 132.5133 106.3179)
		(width 0.2032)
		(layer "F.Cu")
		(net "NetC10_1")
	)
	(segment
		(start 128.7961 108.4301)
		(end 129.2915 108.4301)
		(width 0.508)
		(layer "F.Cu")
		(net "NetC10_1")
	)
	(segment
		(start 131.0591 103.57988)
		(end 131.0591 103.3681)
		(width 0.2032)
		(layer "F.Cu")
		(net "NetC10_1")
	)
	(segment
		(start 132.2125 105.86315)
		(end 132.2125 104.5215)
		(width 0.2032)
		(layer "F.Cu")
		(net "NetC10_1")
	)
	(segment
		(start 127.9961 107.6301)
		(end 128.0461 107.6301)
		(width 0.508)
		(layer "F.Cu")
		(net "NetC10_1")
	)
	(segment
		(start 132.5133 106.3179)
		(end 133.1271 106.3179)
		(width 0.2032)
		(layer "F.Cu")
		(net "NetC10_1")
	)
	(segment
		(start 127.9961 107.6301)
		(end 127.9961 102.12766)
		(width 0.508)
		(layer "F.Cu")
		(net "NetC10_1")
	)
	(segment
		(start 131.36928 103.67828)
		(end 132.2125 104.5215)
		(width 0.2032)
		(layer "F.Cu")
		(net "NetC10_1")
	)
	(segment
		(start 127.9961 107.6301)
		(end 127.9961 107.6301)
		(width 0.508)
		(layer "F.Cu")
		(net "NetC10_1")
	)
	(segment
		(start 128.2421 107.8761)
		(end 128.2421 107.8261)
		(width 0.508)
		(layer "F.Cu")
		(net "NetC10_1")
	)
	(segment
		(start 131.1575 103.67828)
		(end 131.36928 103.67828)
		(width 0.2032)
		(layer "F.Cu")
		(net "NetC10_1")
	)
	(segment
		(start 128.2421 107.8761)
		(end 128.7961 108.4301)
		(width 0.508)
		(layer "F.Cu")
		(net "NetC10_1")
	)
	(segment
		(start 128.0461 107.6301)
		(end 128.2421 107.8261)
		(width 0.508)
		(layer "F.Cu")
		(net "NetC10_1")
	)
	(via
		(at 129.2915 108.4301)
		(size 0.6096)
		(drill 0.3048)
		(layers "F.Cu" "B.Cu")
		(locked yes)
		(tenting
			(front yes)
			(back no)
		)
		(net "NetC10_1")
	)
	(via
		(at 132.1617 105.8901)
		(size 0.6096)
		(drill 0.3048)
		(layers "F.Cu" "B.Cu")
		(locked yes)
		(tenting
			(front yes)
			(back no)
		)
		(net "NetC10_1")
	)
	(segment
		(start 129.2915 108.4301)
		(end 129.2915 107.25884)
		(width 0.2032)
		(layer "In1.Cu")
		(net "NetC10_1")
	)
	(segment
		(start 130.66024 105.8901)
		(end 132.1617 105.8901)
		(width 0.2032)
		(layer "In1.Cu")
		(net "NetC10_1")
	)
	(segment
		(start 129.2915 107.25884)
		(end 130.66024 105.8901)
		(width 0.2032)
		(layer "In1.Cu")
		(net "NetC10_1")
	)
	(segment
		(start 120.70528 101.07619)
		(end 121.56888 101.07619)
		(width 0.1778)
		(layer "F.Cu")
		(net "RF_ANT")
	)
	(segment
		(start 133.82803 101.07619)
		(end 133.91754 101.1657)
		(width 0.1778)
		(layer "F.Cu")
		(net "RF_ANT")
	)
	(segment
		(start 121.56888 101.07619)
		(end 133.82803 101.07619)
		(width 0.1778)
		(layer "F.Cu")
		(net "RF_ANT")
	)
	(segment
		(start 147.4831 95.4841)
		(end 147.80811 95.8091)
		(width 0.254)
		(layer "F.Cu")
		(net "NetC5_1")
	)
	(segment
		(start 147.80811 97.2441)
		(end 147.80811 95.8091)
		(width 0.254)
		(layer "F.Cu")
		(net "NetC5_1")
	)
	(segment
		(start 147.3101 95.3011)
		(end 147.3501 95.3411)
		(width 0.254)
		(layer "F.Cu")
		(net "NetC5_1")
	)
	(segment
		(start 147.3501 95.3411)
		(end 148.8241 95.3411)
		(width 0.254)
		(layer "F.Cu")
		(net "NetC5_1")
	)
	(segment
		(start 147.4831 95.4841)
		(end 147.4831 95.4741)
		(width 0.254)
		(layer "F.Cu")
		(net "NetC5_1")
	)
	(segment
		(start 147.3501 95.3411)
		(end 147.4831 95.4741)
		(width 0.254)
		(layer "F.Cu")
		(net "NetC5_1")
	)
	(segment
		(start 130.35914 106.1885)
		(end 130.35914 105.66806)
		(width 0.2032)
		(layer "F.Cu")
		(net "GND")
	)
	(segment
		(start 147.2901 94.3811)
		(end 147.3001 94.3811)
		(width 0.2032)
		(layer "F.Cu")
		(net "GND")
	)
	(segment
		(start 146.7361 97.2161)
		(end 146.7361 94.89589)
		(width 0.2032)
		(layer "F.Cu")
		(net "GND")
	)
	(segment
		(start 146.96369 94.6683)
		(end 147.0029 94.6683)
		(width 0.2032)
		(layer "F.Cu")
		(net "GND")
	)
	(segment
		(start 117.14928 104.65759)
		(end 117.14928 102.29539)
		(width 0.0127)
		(layer "F.Cu")
		(net "GND")
	)
	(segment
		(start 117.14928 104.65759)
		(end 124.26128 104.65759)
		(width 0.0127)
		(layer "F.Cu")
		(net "GND")
	)
	(segment
		(start 164.1657 106.6521)
		(end 165.1173 106.6521)
		(width 0.2032)
		(layer "F.Cu")
		(net "GND")
	)
	(segment
		(start 130.09815 106.4495)
		(end 130.35914 106.1885)
		(width 0.2032)
		(layer "F.Cu")
		(net "GND")
	)
	(segment
		(start 122.34672 102.29539)
		(end 124.26128 102.29539)
		(width 0.0127)
		(layer "F.Cu")
		(net "GND")
	)
	(segment
		(start 117.14928 99.85699)
		(end 119.06383 99.85699)
		(width 0.0127)
		(layer "F.Cu")
		(net "GND")
	)
	(segment
		(start 129.47254 107.2871)
		(end 129.47254 106.56853)
		(width 0.2032)
		(layer "F.Cu")
		(net "GND")
	)
	(segment
		(start 146.70811 97.2441)
		(end 146.7361 97.2161)
		(width 0.2032)
		(layer "F.Cu")
		(net "GND")
	)
	(segment
		(start 129.47254 106.56853)
		(end 129.59157 106.4495)
		(width 0.2032)
		(layer "F.Cu")
		(net "GND")
	)
	(segment
		(start 122.34672 99.85699)
		(end 124.26128 99.85699)
		(width 0.0127)
		(layer "F.Cu")
		(net "GND")
	)
	(segment
		(start 117.14928 99.85699)
		(end 117.14928 97.49479)
		(width 0.0127)
		(layer "F.Cu")
		(net "GND")
	)
	(segment
		(start 165.1173 106.6521)
		(end 165.1175 106.6523)
		(width 0.2032)
		(layer "F.Cu")
		(net "GND")
	)
	(segment
		(start 124.26128 99.85699)
		(end 124.26128 97.49479)
		(width 0.0127)
		(layer "F.Cu")
		(net "GND")
	)
	(segment
		(start 124.26128 104.65759)
		(end 124.26128 102.29539)
		(width 0.0127)
		(layer "F.Cu")
		(net "GND")
	)
	(segment
		(start 169.23656 109.8525)
		(end 169.23656 109.27744)
		(width 0.2032)
		(layer "F.Cu")
		(net "GND")
	)
	(segment
		(start 169.23656 109.27744)
		(end 169.6267 108.8873)
		(width 0.2032)
		(layer "F.Cu")
		(net "GND")
	)
	(segment
		(start 117.14928 97.49479)
		(end 124.26128 97.49479)
		(width 0.0127)
		(layer "F.Cu")
		(net "GND")
	)
	(segment
		(start 130.35914 105.66806)
		(end 130.4091 105.6181)
		(width 0.2032)
		(layer "F.Cu")
		(net "GND")
	)
	(segment
		(start 147.0029 94.6683)
		(end 147.2901 94.3811)
		(width 0.2032)
		(layer "F.Cu")
		(net "GND")
	)
	(segment
		(start 146.7361 94.89589)
		(end 146.96369 94.6683)
		(width 0.2032)
		(layer "F.Cu")
		(net "GND")
	)
	(segment
		(start 117.14928 102.29539)
		(end 119.06383 102.29539)
		(width 0.0127)
		(layer "F.Cu")
		(net "GND")
	)
	(segment
		(start 129.59157 106.4495)
		(end 130.09815 106.4495)
		(width 0.2032)
		(layer "F.Cu")
		(net "GND")
	)
	(via
		(at 164.1657 106.6521)
		(size 0.6096)
		(drill 0.3048)
		(layers "F.Cu" "B.Cu")
		(locked yes)
		(tenting
			(front yes)
			(back no)
		)
		(net "GND")
	)
	(via
		(at 130.50048 101.68711)
		(size 0.6096)
		(drill 0.3048)
		(layers "F.Cu" "B.Cu")
		(locked yes)
		(tenting
			(front yes)
			(back no)
		)
		(net "GND")
	)
	(via
		(at 170.65975 95.35945)
		(size 0.6096)
		(drill 0.3048)
		(layers "F.Cu" "B.Cu")
		(locked yes)
		(tenting
			(front yes)
			(back no)
		)
		(net "GND")
	)
	(via
		(at 131.9549 100.46527)
		(size 0.6096)
		(drill 0.3048)
		(layers "F.Cu" "B.Cu")
		(locked yes)
		(tenting
			(front yes)
			(back no)
		)
		(net "GND")
	)
	(via
		(at 119.70908 100.11383)
		(size 0.6096)
		(drill 0.3048)
		(layers "F.Cu" "B.Cu")
		(locked yes)
		(tenting
			(front yes)
			(back no)
		)
		(net "GND")
	)
	(via
		(at 119.85975 110.59945)
		(size 0.6096)
		(drill 0.3048)
		(layers "F.Cu" "B.Cu")
		(locked yes)
		(tenting
			(front yes)
			(back no)
		)
		(net "GND")
	)
	(via
		(at 124.08172 101.68711)
		(size 0.6096)
		(drill 0.3048)
		(layers "F.Cu" "B.Cu")
		(locked yes)
		(tenting
			(front yes)
			(back no)
		)
		(net "GND")
	)
	(via
		(at 120.99956 99.71835)
		(size 0.6096)
		(drill 0.3048)
		(layers "F.Cu" "B.Cu")
		(locked yes)
		(tenting
			(front yes)
			(back no)
		)
		(net "GND")
	)
	(via
		(at 129.38288 101.68711)
		(size 0.6096)
		(drill 0.3048)
		(layers "F.Cu" "B.Cu")
		(locked yes)
		(tenting
			(front yes)
			(back no)
		)
		(net "GND")
	)
	(via
		(at 129.7197 100.46527)
		(size 0.6096)
		(drill 0.3048)
		(layers "F.Cu" "B.Cu")
		(locked yes)
		(tenting
			(front yes)
			(back no)
		)
		(net "GND")
	)
	(via
		(at 147.79975 115.67945)
		(size 0.6096)
		(drill 0.3048)
		(layers "F.Cu" "B.Cu")
		(locked yes)
		(tenting
			(front yes)
			(back no)
		)
		(net "GND")
	)
	(via
		(at 137.63975 95.35945)
		(size 0.6096)
		(drill 0.3048)
		(layers "F.Cu" "B.Cu")
		(locked yes)
		(tenting
			(front yes)
			(back no)
		)
		(net "GND")
	)
	(via
		(at 124.93975 113.13945)
		(size 0.6096)
		(drill 0.3048)
		(layers "F.Cu" "B.Cu")
		(locked yes)
		(tenting
			(front yes)
			(back no)
		)
		(net "GND")
	)
	(via
		(at 132.73568 101.68711)
		(size 0.6096)
		(drill 0.3048)
		(layers "F.Cu" "B.Cu")
		(locked yes)
		(tenting
			(front yes)
			(back no)
		)
		(net "GND")
	)
	(via
		(at 147.79975 90.27945)
		(size 0.6096)
		(drill 0.3048)
		(layers "F.Cu" "B.Cu")
		(locked yes)
		(tenting
			(front yes)
			(back no)
		)
		(net "GND")
	)
	(via
		(at 132.55975 108.05945)
		(size 0.6096)
		(drill 0.3048)
		(layers "F.Cu" "B.Cu")
		(locked yes)
		(tenting
			(front yes)
			(back no)
		)
		(net "GND")
	)
	(via
		(at 180.81975 92.81945)
		(size 0.6096)
		(drill 0.3048)
		(layers "F.Cu" "B.Cu")
		(locked yes)
		(tenting
			(front yes)
			(back no)
		)
		(net "GND")
	)
	(via
		(at 148.84315 111.4019)
		(size 0.6096)
		(drill 0.3048)
		(layers "F.Cu" "B.Cu")
		(locked yes)
		(tenting
			(front yes)
			(back no)
		)
		(net "GND")
	)
	(via
		(at 127.47975 115.67945)
		(size 0.6096)
		(drill 0.3048)
		(layers "F.Cu" "B.Cu")
		(locked yes)
		(tenting
			(front yes)
			(back no)
		)
		(net "GND")
	)
	(via
		(at 144.63945 107.1347)
		(size 0.6096)
		(drill 0.3048)
		(layers "F.Cu" "B.Cu")
		(locked yes)
		(tenting
			(front yes)
			(back no)
		)
		(net "GND")
	)
	(via
		(at 150.9577 102.9945)
		(size 0.6096)
		(drill 0.3048)
		(layers "F.Cu" "B.Cu")
		(locked yes)
		(tenting
			(front yes)
			(back no)
		)
		(net "GND")
	)
	(via
		(at 144.61405 100.8609)
		(size 0.6096)
		(drill 0.3048)
		(layers "F.Cu" "B.Cu")
		(locked yes)
		(tenting
			(front yes)
			(back no)
		)
		(net "GND")
	)
	(via
		(at 173.19975 90.27945)
		(size 0.6096)
		(drill 0.3048)
		(layers "F.Cu" "B.Cu")
		(locked yes)
		(tenting
			(front yes)
			(back no)
		)
		(net "GND")
	)
	(via
		(at 175.73975 108.05945)
		(size 0.6096)
		(drill 0.3048)
		(layers "F.Cu" "B.Cu")
		(locked yes)
		(tenting
			(front yes)
			(back no)
		)
		(net "GND")
	)
	(via
		(at 136.35035 101.77661)
		(size 0.6096)
		(drill 0.3048)
		(layers "F.Cu" "B.Cu")
		(locked yes)
		(tenting
			(front yes)
			(back no)
		)
		(net "GND")
	)
	(via
		(at 117.31975 100.43945)
		(size 0.6096)
		(drill 0.3048)
		(layers "F.Cu" "B.Cu")
		(locked yes)
		(tenting
			(front yes)
			(back no)
		)
		(net "GND")
	)
	(via
		(at 119.85975 105.51945)
		(size 0.6096)
		(drill 0.3048)
		(layers "F.Cu" "B.Cu")
		(locked yes)
		(tenting
			(front yes)
			(back no)
		)
		(net "GND")
	)
	(via
		(at 119.8347 102.15347)
		(size 0.6096)
		(drill 0.3048)
		(layers "F.Cu" "B.Cu")
		(locked yes)
		(tenting
			(front yes)
			(back no)
		)
		(net "GND")
	)
	(via
		(at 173.19975 95.35945)
		(size 0.6096)
		(drill 0.3048)
		(layers "F.Cu" "B.Cu")
		(locked yes)
		(tenting
			(front yes)
			(back no)
		)
		(net "GND")
	)
	(via
		(at 122.39975 92.81945)
		(size 0.6096)
		(drill 0.3048)
		(layers "F.Cu" "B.Cu")
		(locked yes)
		(tenting
			(front yes)
			(back no)
		)
		(net "GND")
	)
	(via
		(at 130.01975 118.21945)
		(size 0.6096)
		(drill 0.3048)
		(layers "F.Cu" "B.Cu")
		(locked yes)
		(tenting
			(front yes)
			(back no)
		)
		(net "GND")
	)
	(via
		(at 122.39975 95.35945)
		(size 0.6096)
		(drill 0.3048)
		(layers "F.Cu" "B.Cu")
		(locked yes)
		(tenting
			(front yes)
			(back no)
		)
		(net "GND")
	)
	(via
		(at 180.81975 95.35945)
		(size 0.6096)
		(drill 0.3048)
		(layers "F.Cu" "B.Cu")
		(locked yes)
		(tenting
			(front yes)
			(back no)
		)
		(net "GND")
	)
	(via
		(at 163.03975 108.05945)
		(size 0.6096)
		(drill 0.3048)
		(layers "F.Cu" "B.Cu")
		(locked yes)
		(tenting
			(front yes)
			(back no)
		)
		(net "GND")
	)
	(via
		(at 132.55975 90.27945)
		(size 0.6096)
		(drill 0.3048)
		(layers "F.Cu" "B.Cu")
		(locked yes)
		(tenting
			(front yes)
			(back no)
		)
		(net "GND")
	)
	(via
		(at 180.81975 90.27945)
		(size 0.6096)
		(drill 0.3048)
		(layers "F.Cu" "B.Cu")
		(locked yes)
		(tenting
			(front yes)
			(back no)
		)
		(net "GND")
	)
	(via
		(at 127.47975 118.21945)
		(size 0.6096)
		(drill 0.3048)
		(layers "F.Cu" "B.Cu")
		(locked yes)
		(tenting
			(front yes)
			(back no)
		)
		(net "GND")
	)
	(via
		(at 142.71975 115.67945)
		(size 0.6096)
		(drill 0.3048)
		(layers "F.Cu" "B.Cu")
		(locked yes)
		(tenting
			(front yes)
			(back no)
		)
		(net "GND")
	)
	(via
		(at 142.5249 109.2683)
		(size 0.6096)
		(drill 0.3048)
		(layers "F.Cu" "B.Cu")
		(locked yes)
		(tenting
			(front yes)
			(back no)
		)
		(net "GND")
	)
	(via
		(at 163.03975 90.27945)
		(size 0.6096)
		(drill 0.3048)
		(layers "F.Cu" "B.Cu")
		(locked yes)
		(tenting
			(front yes)
			(back no)
		)
		(net "GND")
	)
	(via
		(at 127.47975 113.13945)
		(size 0.6096)
		(drill 0.3048)
		(layers "F.Cu" "B.Cu")
		(locked yes)
		(tenting
			(front yes)
			(back no)
		)
		(net "GND")
	)
	(via
		(at 180.81975 113.13945)
		(size 0.6096)
		(drill 0.3048)
		(layers "F.Cu" "B.Cu")
		(locked yes)
		(tenting
			(front yes)
			(back no)
		)
		(net "GND")
	)
	(via
		(at 157.95975 105.51945)
		(size 0.6096)
		(drill 0.3048)
		(layers "F.Cu" "B.Cu")
		(locked yes)
		(tenting
			(front yes)
			(back no)
		)
		(net "GND")
	)
	(via
		(at 152.87975 90.27945)
		(size 0.6096)
		(drill 0.3048)
		(layers "F.Cu" "B.Cu")
		(locked yes)
		(tenting
			(front yes)
			(back no)
		)
		(net "GND")
	)
	(via
		(at 142.4995 102.9945)
		(size 0.6096)
		(drill 0.3048)
		(layers "F.Cu" "B.Cu")
		(locked yes)
		(tenting
			(front yes)
			(back no)
		)
		(net "GND")
	)
	(via
		(at 155.41975 115.67945)
		(size 0.6096)
		(drill 0.3048)
		(layers "F.Cu" "B.Cu")
		(locked yes)
		(tenting
			(front yes)
			(back no)
		)
		(net "GND")
	)
	(via
		(at 148.86855 113.5101)
		(size 0.6096)
		(drill 0.3048)
		(layers "F.Cu" "B.Cu")
		(locked yes)
		(tenting
			(front yes)
			(back no)
		)
		(net "GND")
	)
	(via
		(at 155.41975 97.89945)
		(size 0.6096)
		(drill 0.3048)
		(layers "F.Cu" "B.Cu")
		(locked yes)
		(tenting
			(front yes)
			(back no)
		)
		(net "GND")
	)
	(via
		(at 180.81975 108.05945)
		(size 0.6096)
		(drill 0.3048)
		(layers "F.Cu" "B.Cu")
		(locked yes)
		(tenting
			(front yes)
			(back no)
		)
		(net "GND")
	)
	(via
		(at 168.11975 90.27945)
		(size 0.6096)
		(drill 0.3048)
		(layers "F.Cu" "B.Cu")
		(locked yes)
		(tenting
			(front yes)
			(back no)
		)
		(net "GND")
	)
	(via
		(at 124.93975 92.81945)
		(size 0.6096)
		(drill 0.3048)
		(layers "F.Cu" "B.Cu")
		(locked yes)
		(tenting
			(front yes)
			(back no)
		)
		(net "GND")
	)
	(via
		(at 121.90073 100.37935)
		(size 0.6096)
		(drill 0.3048)
		(layers "F.Cu" "B.Cu")
		(locked yes)
		(tenting
			(front yes)
			(back no)
		)
		(net "GND")
	)
	(via
		(at 122.39975 108.05945)
		(size 0.6096)
		(drill 0.3048)
		(layers "F.Cu" "B.Cu")
		(locked yes)
		(tenting
			(front yes)
			(back no)
		)
		(net "GND")
	)
	(via
		(at 127.47975 97.89945)
		(size 0.6096)
		(drill 0.3048)
		(layers "F.Cu" "B.Cu")
		(locked yes)
		(tenting
			(front yes)
			(back no)
		)
		(net "GND")
	)
	(via
		(at 160.49975 115.67945)
		(size 0.6096)
		(drill 0.3048)
		(layers "F.Cu" "B.Cu")
		(locked yes)
		(tenting
			(front yes)
			(back no)
		)
		(net "GND")
	)
	(via
		(at 140.17975 115.67945)
		(size 0.6096)
		(drill 0.3048)
		(layers "F.Cu" "B.Cu")
		(locked yes)
		(tenting
			(front yes)
			(back no)
		)
		(net "GND")
	)
	(via
		(at 124.93975 102.97945)
		(size 0.6096)
		(drill 0.3048)
		(layers "F.Cu" "B.Cu")
		(locked yes)
		(tenting
			(front yes)
			(back no)
		)
		(net "GND")
	)
	(via
		(at 122.39975 118.21945)
		(size 0.6096)
		(drill 0.3048)
		(layers "F.Cu" "B.Cu")
		(locked yes)
		(tenting
			(front yes)
			(back no)
		)
		(net "GND")
	)
	(via
		(at 146.7286 105.1027)
		(size 0.6096)
		(drill 0.3048)
		(layers "F.Cu" "B.Cu")
		(locked yes)
		(tenting
			(front yes)
			(back no)
		)
		(net "GND")
	)
	(via
		(at 144.61405 111.4019)
		(size 0.6096)
		(drill 0.3048)
		(layers "F.Cu" "B.Cu")
		(locked yes)
		(tenting
			(front yes)
			(back no)
		)
		(net "GND")
	)
	(via
		(at 178.27975 97.89945)
		(size 0.6096)
		(drill 0.3048)
		(layers "F.Cu" "B.Cu")
		(locked yes)
		(tenting
			(front yes)
			(back no)
		)
		(net "GND")
	)
	(via
		(at 127.47975 95.35945)
		(size 0.6096)
		(drill 0.3048)
		(layers "F.Cu" "B.Cu")
		(locked yes)
		(tenting
			(front yes)
			(back no)
		)
		(net "GND")
	)
	(via
		(at 140.17975 92.81945)
		(size 0.6096)
		(drill 0.3048)
		(layers "F.Cu" "B.Cu")
		(locked yes)
		(tenting
			(front yes)
			(back no)
		)
		(net "GND")
	)
	(via
		(at 137.63975 113.13945)
		(size 0.6096)
		(drill 0.3048)
		(layers "F.Cu" "B.Cu")
		(locked yes)
		(tenting
			(front yes)
			(back no)
		)
		(net "GND")
	)
	(via
		(at 146.7286 111.4019)
		(size 0.6096)
		(drill 0.3048)
		(layers "F.Cu" "B.Cu")
		(locked yes)
		(tenting
			(front yes)
			(back no)
		)
		(net "GND")
	)
	(via
		(at 127.47975 110.59945)
		(size 0.6096)
		(drill 0.3048)
		(layers "F.Cu" "B.Cu")
		(locked yes)
		(tenting
			(front yes)
			(back no)
		)
		(net "GND")
	)
	(via
		(at 144.63945 113.5101)
		(size 0.6096)
		(drill 0.3048)
		(layers "F.Cu" "B.Cu")
		(locked yes)
		(tenting
			(front yes)
			(back no)
		)
		(net "GND")
	)
	(via
		(at 150.33975 115.67945)
		(size 0.6096)
		(drill 0.3048)
		(layers "F.Cu" "B.Cu")
		(locked yes)
		(tenting
			(front yes)
			(back no)
		)
		(net "GND")
	)
	(via
		(at 173.19975 105.51945)
		(size 0.6096)
		(drill 0.3048)
		(layers "F.Cu" "B.Cu")
		(locked yes)
		(tenting
			(front yes)
			(back no)
		)
		(net "GND")
	)
	(via
		(at 148.86855 109.2683)
		(size 0.6096)
		(drill 0.3048)
		(layers "F.Cu" "B.Cu")
		(locked yes)
		(tenting
			(front yes)
			(back no)
		)
		(net "GND")
	)
	(via
		(at 124.93975 90.27945)
		(size 0.6096)
		(drill 0.3048)
		(layers "F.Cu" "B.Cu")
		(locked yes)
		(tenting
			(front yes)
			(back no)
		)
		(net "GND")
	)
	(via
		(at 137.63975 110.59945)
		(size 0.6096)
		(drill 0.3048)
		(layers "F.Cu" "B.Cu")
		(locked yes)
		(tenting
			(front yes)
			(back no)
		)
		(net "GND")
	)
	(via
		(at 173.19975 100.43945)
		(size 0.6096)
		(drill 0.3048)
		(layers "F.Cu" "B.Cu")
		(locked yes)
		(tenting
			(front yes)
			(back no)
		)
		(net "GND")
	)
	(via
		(at 160.49975 110.59945)
		(size 0.6096)
		(drill 0.3048)
		(layers "F.Cu" "B.Cu")
		(locked yes)
		(tenting
			(front yes)
			(back no)
		)
		(net "GND")
	)
	(via
		(at 126.36736 100.43313)
		(size 0.6096)
		(drill 0.3048)
		(layers "F.Cu" "B.Cu")
		(locked yes)
		(tenting
			(front yes)
			(back no)
		)
		(net "GND")
	)
	(via
		(at 144.61405 102.9945)
		(size 0.6096)
		(drill 0.3048)
		(layers "F.Cu" "B.Cu")
		(locked yes)
		(tenting
			(front yes)
			(back no)
		)
		(net "GND")
	)
	(via
		(at 123.01502 100.46527)
		(size 0.6096)
		(drill 0.3048)
		(layers "F.Cu" "B.Cu")
		(locked yes)
		(tenting
			(front yes)
			(back no)
		)
		(net "GND")
	)
	(via
		(at 163.03975 118.21945)
		(size 0.6096)
		(drill 0.3048)
		(layers "F.Cu" "B.Cu")
		(locked yes)
		(tenting
			(front yes)
			(back no)
		)
		(net "GND")
	)
	(via
		(at 157.95975 113.13945)
		(size 0.6096)
		(drill 0.3048)
		(layers "F.Cu" "B.Cu")
		(locked yes)
		(tenting
			(front yes)
			(back no)
		)
		(net "GND")
	)
	(via
		(at 119.85975 95.35945)
		(size 0.6096)
		(drill 0.3048)
		(layers "F.Cu" "B.Cu")
		(locked yes)
		(tenting
			(front yes)
			(back no)
		)
		(net "GND")
	)
	(via
		(at 163.03975 97.89945)
		(size 0.6096)
		(drill 0.3048)
		(layers "F.Cu" "B.Cu")
		(locked yes)
		(tenting
			(front yes)
			(back no)
		)
		(net "GND")
	)
	(via
		(at 150.9577 100.8609)
		(size 0.6096)
		(drill 0.3048)
		(layers "F.Cu" "B.Cu")
		(locked yes)
		(tenting
			(front yes)
			(back no)
		)
		(net "GND")
	)
	(via
		(at 124.13262 100.46527)
		(size 0.6096)
		(drill 0.3048)
		(layers "F.Cu" "B.Cu")
		(locked yes)
		(tenting
			(front yes)
			(back no)
		)
		(net "GND")
	)
	(via
		(at 137.63975 118.21945)
		(size 0.6096)
		(drill 0.3048)
		(layers "F.Cu" "B.Cu")
		(locked yes)
		(tenting
			(front yes)
			(back no)
		)
		(net "GND")
	)
	(via
		(at 163.03975 113.13945)
		(size 0.6096)
		(drill 0.3048)
		(layers "F.Cu" "B.Cu")
		(locked yes)
		(tenting
			(front yes)
			(back no)
		)
		(net "GND")
	)
	(via
		(at 117.31975 102.97945)
		(size 0.6096)
		(drill 0.3048)
		(layers "F.Cu" "B.Cu")
		(locked yes)
		(tenting
			(front yes)
			(back no)
		)
		(net "GND")
	)
	(via
		(at 137.63975 108.05945)
		(size 0.6096)
		(drill 0.3048)
		(layers "F.Cu" "B.Cu")
		(locked yes)
		(tenting
			(front yes)
			(back no)
		)
		(net "GND")
	)
	(via
		(at 136.14138 100.55478)
		(size 0.6096)
		(drill 0.3048)
		(layers "F.Cu" "B.Cu")
		(locked yes)
		(tenting
			(front yes)
			(back no)
		)
		(net "GND")
	)
	(via
		(at 137.63975 97.89945)
		(size 0.6096)
		(drill 0.3048)
		(layers "F.Cu" "B.Cu")
		(locked yes)
		(tenting
			(front yes)
			(back no)
		)
		(net "GND")
	)
	(via
		(at 160.49975 108.05945)
		(size 0.6096)
		(drill 0.3048)
		(layers "F.Cu" "B.Cu")
		(locked yes)
		(tenting
			(front yes)
			(back no)
		)
		(net "GND")
	)
	(via
		(at 168.11975 105.51945)
		(size 0.6096)
		(drill 0.3048)
		(layers "F.Cu" "B.Cu")
		(locked yes)
		(tenting
			(front yes)
			(back no)
		)
		(net "GND")
	)
	(via
		(at 165.57975 90.27945)
		(size 0.6096)
		(drill 0.3048)
		(layers "F.Cu" "B.Cu")
		(locked yes)
		(tenting
			(front yes)
			(back no)
		)
		(net "GND")
	)
	(via
		(at 144.63945 109.2683)
		(size 0.6096)
		(drill 0.3048)
		(layers "F.Cu" "B.Cu")
		(locked yes)
		(tenting
			(front yes)
			(back no)
		)
		(net "GND")
	)
	(via
		(at 155.41975 90.27945)
		(size 0.6096)
		(drill 0.3048)
		(layers "F.Cu" "B.Cu")
		(locked yes)
		(tenting
			(front yes)
			(back no)
		)
		(net "GND")
	)
	(via
		(at 170.65975 92.81945)
		(size 0.6096)
		(drill 0.3048)
		(layers "F.Cu" "B.Cu")
		(locked yes)
		(tenting
			(front yes)
			(back no)
		)
		(net "GND")
	)
	(via
		(at 145.25975 115.67945)
		(size 0.6096)
		(drill 0.3048)
		(layers "F.Cu" "B.Cu")
		(locked yes)
		(tenting
			(front yes)
			(back no)
		)
		(net "GND")
	)
	(via
		(at 150.9577 105.1027)
		(size 0.6096)
		(drill 0.3048)
		(layers "F.Cu" "B.Cu")
		(locked yes)
		(tenting
			(front yes)
			(back no)
		)
		(net "GND")
	)
	(via
		(at 148.84315 102.9945)
		(size 0.6096)
		(drill 0.3048)
		(layers "F.Cu" "B.Cu")
		(locked yes)
		(tenting
			(front yes)
			(back no)
		)
		(net "GND")
	)
	(via
		(at 168.11975 92.81945)
		(size 0.6096)
		(drill 0.3048)
		(layers "F.Cu" "B.Cu")
		(locked yes)
		(tenting
			(front yes)
			(back no)
		)
		(net "GND")
	)
	(via
		(at 146.754 109.2683)
		(size 0.6096)
		(drill 0.3048)
		(layers "F.Cu" "B.Cu")
		(locked yes)
		(tenting
			(front yes)
			(back no)
		)
		(net "GND")
	)
	(via
		(at 117.31975 108.05945)
		(size 0.6096)
		(drill 0.3048)
		(layers "F.Cu" "B.Cu")
		(locked yes)
		(tenting
			(front yes)
			(back no)
		)
		(net "GND")
	)
	(via
		(at 119.85975 113.13945)
		(size 0.6096)
		(drill 0.3048)
		(layers "F.Cu" "B.Cu")
		(locked yes)
		(tenting
			(front yes)
			(back no)
		)
		(net "GND")
	)
	(via
		(at 122.39975 105.51945)
		(size 0.6096)
		(drill 0.3048)
		(layers "F.Cu" "B.Cu")
		(locked yes)
		(tenting
			(front yes)
			(back no)
		)
		(net "GND")
	)
	(via
		(at 125.25022 100.46527)
		(size 0.6096)
		(drill 0.3048)
		(layers "F.Cu" "B.Cu")
		(locked yes)
		(tenting
			(front yes)
			(back no)
		)
		(net "GND")
	)
	(via
		(at 140.17975 90.27945)
		(size 0.6096)
		(drill 0.3048)
		(layers "F.Cu" "B.Cu")
		(locked yes)
		(tenting
			(front yes)
			(back no)
		)
		(net "GND")
	)
	(via
		(at 122.39975 113.13945)
		(size 0.6096)
		(drill 0.3048)
		(layers "F.Cu" "B.Cu")
		(locked yes)
		(tenting
			(front yes)
			(back no)
		)
		(net "GND")
	)
	(via
		(at 127.4845 100.46527)
		(size 0.6096)
		(drill 0.3048)
		(layers "F.Cu" "B.Cu")
		(locked yes)
		(tenting
			(front yes)
			(back no)
		)
		(net "GND")
	)
	(via
		(at 134.18557 100.36477)
		(size 0.6096)
		(drill 0.3048)
		(layers "F.Cu" "B.Cu")
		(locked yes)
		(tenting
			(front yes)
			(back no)
		)
		(net "GND")
	)
	(via
		(at 142.4995 105.1027)
		(size 0.6096)
		(drill 0.3048)
		(layers "F.Cu" "B.Cu")
		(locked yes)
		(tenting
			(front yes)
			(back no)
		)
		(net "GND")
	)
	(via
		(at 144.61405 105.1027)
		(size 0.6096)
		(drill 0.3048)
		(layers "F.Cu" "B.Cu")
		(locked yes)
		(tenting
			(front yes)
			(back no)
		)
		(net "GND")
	)
	(via
		(at 148.84315 100.8609)
		(size 0.6096)
		(drill 0.3048)
		(layers "F.Cu" "B.Cu")
		(locked yes)
		(tenting
			(front yes)
			(back no)
		)
		(net "GND")
	)
	(via
		(at 137.63975 92.81945)
		(size 0.6096)
		(drill 0.3048)
		(layers "F.Cu" "B.Cu")
		(locked yes)
		(tenting
			(front yes)
			(back no)
		)
		(net "GND")
	)
	(via
		(at 157.95975 90.27945)
		(size 0.6096)
		(drill 0.3048)
		(layers "F.Cu" "B.Cu")
		(locked yes)
		(tenting
			(front yes)
			(back no)
		)
		(net "GND")
	)
	(via
		(at 175.73975 95.35945)
		(size 0.6096)
		(drill 0.3048)
		(layers "F.Cu" "B.Cu")
		(locked yes)
		(tenting
			(front yes)
			(back no)
		)
		(net "GND")
	)
	(via
		(at 135.09975 92.81945)
		(size 0.6096)
		(drill 0.3048)
		(layers "F.Cu" "B.Cu")
		(locked yes)
		(tenting
			(front yes)
			(back no)
		)
		(net "GND")
	)
	(via
		(at 142.5249 107.1347)
		(size 0.6096)
		(drill 0.3048)
		(layers "F.Cu" "B.Cu")
		(locked yes)
		(tenting
			(front yes)
			(back no)
		)
		(net "GND")
	)
	(via
		(at 132.55975 97.89945)
		(size 0.6096)
		(drill 0.3048)
		(layers "F.Cu" "B.Cu")
		(locked yes)
		(tenting
			(front yes)
			(back no)
		)
		(net "GND")
	)
	(via
		(at 175.73975 105.51945)
		(size 0.6096)
		(drill 0.3048)
		(layers "F.Cu" "B.Cu")
		(locked yes)
		(tenting
			(front yes)
			(back no)
		)
		(net "GND")
	)
	(via
		(at 173.19975 102.97945)
		(size 0.6096)
		(drill 0.3048)
		(layers "F.Cu" "B.Cu")
		(locked yes)
		(tenting
			(front yes)
			(back no)
		)
		(net "GND")
	)
	(via
		(at 163.03975 105.51945)
		(size 0.6096)
		(drill 0.3048)
		(layers "F.Cu" "B.Cu")
		(locked yes)
		(tenting
			(front yes)
			(back no)
		)
		(net "GND")
	)
	(via
		(at 180.81975 105.51945)
		(size 0.6096)
		(drill 0.3048)
		(layers "F.Cu" "B.Cu")
		(locked yes)
		(tenting
			(front yes)
			(back no)
		)
		(net "GND")
	)
	(via
		(at 135.24396 101.93448)
		(size 0.6096)
		(drill 0.3048)
		(layers "F.Cu" "B.Cu")
		(locked yes)
		(tenting
			(front yes)
			(back no)
		)
		(net "GND")
	)
	(via
		(at 132.55975 95.35945)
		(size 0.6096)
		(drill 0.3048)
		(layers "F.Cu" "B.Cu")
		(locked yes)
		(tenting
			(front yes)
			(back no)
		)
		(net "GND")
	)
	(via
		(at 119.31992 101.16149)
		(size 0.6096)
		(drill 0.3048)
		(layers "F.Cu" "B.Cu")
		(locked yes)
		(tenting
			(front yes)
			(back no)
		)
		(net "GND")
	)
	(via
		(at 165.57975 100.43945)
		(size 0.6096)
		(drill 0.3048)
		(layers "F.Cu" "B.Cu")
		(locked yes)
		(tenting
			(front yes)
			(back no)
		)
		(net "GND")
	)
	(via
		(at 142.5249 113.5101)
		(size 0.6096)
		(drill 0.3048)
		(layers "F.Cu" "B.Cu")
		(locked yes)
		(tenting
			(front yes)
			(back no)
		)
		(net "GND")
	)
	(via
		(at 122.96412 101.68711)
		(size 0.6096)
		(drill 0.3048)
		(layers "F.Cu" "B.Cu")
		(locked yes)
		(tenting
			(front yes)
			(back no)
		)
		(net "GND")
	)
	(via
		(at 117.31975 105.51945)
		(size 0.6096)
		(drill 0.3048)
		(layers "F.Cu" "B.Cu")
		(locked yes)
		(tenting
			(front yes)
			(back no)
		)
		(net "GND")
	)
	(via
		(at 142.4995 100.8609)
		(size 0.6096)
		(drill 0.3048)
		(layers "F.Cu" "B.Cu")
		(locked yes)
		(tenting
			(front yes)
			(back no)
		)
		(net "GND")
	)
	(via
		(at 175.73975 92.81945)
		(size 0.6096)
		(drill 0.3048)
		(layers "F.Cu" "B.Cu")
		(locked yes)
		(tenting
			(front yes)
			(back no)
		)
		(net "GND")
	)
	(via
		(at 173.19975 97.89945)
		(size 0.6096)
		(drill 0.3048)
		(layers "F.Cu" "B.Cu")
		(locked yes)
		(tenting
			(front yes)
			(back no)
		)
		(net "GND")
	)
	(via
		(at 130.01975 97.89945)
		(size 0.6096)
		(drill 0.3048)
		(layers "F.Cu" "B.Cu")
		(locked yes)
		(tenting
			(front yes)
			(back no)
		)
		(net "GND")
	)
	(via
		(at 122.39975 115.67945)
		(size 0.6096)
		(drill 0.3048)
		(layers "F.Cu" "B.Cu")
		(locked yes)
		(tenting
			(front yes)
			(back no)
		)
		(net "GND")
	)
	(via
		(at 175.73975 90.27945)
		(size 0.6096)
		(drill 0.3048)
		(layers "F.Cu" "B.Cu")
		(locked yes)
		(tenting
			(front yes)
			(back no)
		)
		(net "GND")
	)
	(via
		(at 148.84315 105.1027)
		(size 0.6096)
		(drill 0.3048)
		(layers "F.Cu" "B.Cu")
		(locked yes)
		(tenting
			(front yes)
			(back no)
		)
		(net "GND")
	)
	(via
		(at 117.31975 115.67945)
		(size 0.6096)
		(drill 0.3048)
		(layers "F.Cu" "B.Cu")
		(locked yes)
		(tenting
			(front yes)
			(back no)
		)
		(net "GND")
	)
	(via
		(at 148.86855 107.1347)
		(size 0.6096)
		(drill 0.3048)
		(layers "F.Cu" "B.Cu")
		(locked yes)
		(tenting
			(front yes)
			(back no)
		)
		(net "GND")
	)
	(via
		(at 132.55975 92.81945)
		(size 0.6096)
		(drill 0.3048)
		(layers "F.Cu" "B.Cu")
		(locked yes)
		(tenting
			(front yes)
			(back no)
		)
		(net "GND")
	)
	(via
		(at 137.63975 90.27945)
		(size 0.6096)
		(drill 0.3048)
		(layers "F.Cu" "B.Cu")
		(locked yes)
		(tenting
			(front yes)
			(back no)
		)
		(net "GND")
	)
	(via
		(at 134.1683 101.9785)
		(size 0.6096)
		(drill 0.3048)
		(layers "F.Cu" "B.Cu")
		(locked yes)
		(tenting
			(front yes)
			(back no)
		)
		(net "GND")
	)
	(via
		(at 122.39975 110.59945)
		(size 0.6096)
		(drill 0.3048)
		(layers "F.Cu" "B.Cu")
		(locked yes)
		(tenting
			(front yes)
			(back no)
		)
		(net "GND")
	)
	(via
		(at 133.0725 100.46527)
		(size 0.6096)
		(drill 0.3048)
		(layers "F.Cu" "B.Cu")
		(locked yes)
		(tenting
			(front yes)
			(back no)
		)
		(net "GND")
	)
	(via
		(at 127.47975 90.27945)
		(size 0.6096)
		(drill 0.3048)
		(layers "F.Cu" "B.Cu")
		(locked yes)
		(tenting
			(front yes)
			(back no)
		)
		(net "GND")
	)
	(via
		(at 124.93975 95.35945)
		(size 0.6096)
		(drill 0.3048)
		(layers "F.Cu" "B.Cu")
		(locked yes)
		(tenting
			(front yes)
			(back no)
		)
		(net "GND")
	)
	(via
		(at 125.12633 102.08437)
		(size 0.6096)
		(drill 0.3048)
		(layers "F.Cu" "B.Cu")
		(locked yes)
		(tenting
			(front yes)
			(back no)
		)
		(net "GND")
	)
	(via
		(at 160.49975 105.51945)
		(size 0.6096)
		(drill 0.3048)
		(layers "F.Cu" "B.Cu")
		(locked yes)
		(tenting
			(front yes)
			(back no)
		)
		(net "GND")
	)
	(via
		(at 145.25975 90.27945)
		(size 0.6096)
		(drill 0.3048)
		(layers "F.Cu" "B.Cu")
		(locked yes)
		(tenting
			(front yes)
			(back no)
		)
		(net "GND")
	)
	(via
		(at 119.85975 90.27945)
		(size 0.6096)
		(drill 0.3048)
		(layers "F.Cu" "B.Cu")
		(locked yes)
		(tenting
			(front yes)
			(back no)
		)
		(net "GND")
	)
	(via
		(at 117.31975 113.13945)
		(size 0.6096)
		(drill 0.3048)
		(layers "F.Cu" "B.Cu")
		(locked yes)
		(tenting
			(front yes)
			(back no)
		)
		(net "GND")
	)
	(via
		(at 155.41975 102.97945)
		(size 0.6096)
		(drill 0.3048)
		(layers "F.Cu" "B.Cu")
		(locked yes)
		(tenting
			(front yes)
			(back no)
		)
		(net "GND")
	)
	(via
		(at 178.27975 95.35945)
		(size 0.6096)
		(drill 0.3048)
		(layers "F.Cu" "B.Cu")
		(locked yes)
		(tenting
			(front yes)
			(back no)
		)
		(net "GND")
	)
	(via
		(at 175.73975 115.67945)
		(size 0.6096)
		(drill 0.3048)
		(layers "F.Cu" "B.Cu")
		(locked yes)
		(tenting
			(front yes)
			(back no)
		)
		(net "GND")
	)
	(via
		(at 180.81975 118.21945)
		(size 0.6096)
		(drill 0.3048)
		(layers "F.Cu" "B.Cu")
		(locked yes)
		(tenting
			(front yes)
			(back no)
		)
		(net "GND")
	)
	(via
		(at 160.49975 90.27945)
		(size 0.6096)
		(drill 0.3048)
		(layers "F.Cu" "B.Cu")
		(locked yes)
		(tenting
			(front yes)
			(back no)
		)
		(net "GND")
	)
	(via
		(at 132.55975 115.67945)
		(size 0.6096)
		(drill 0.3048)
		(layers "F.Cu" "B.Cu")
		(locked yes)
		(tenting
			(front yes)
			(back no)
		)
		(net "GND")
	)
	(via
		(at 124.93975 110.59945)
		(size 0.6096)
		(drill 0.3048)
		(layers "F.Cu" "B.Cu")
		(locked yes)
		(tenting
			(front yes)
			(back no)
		)
		(net "GND")
	)
	(via
		(at 157.95975 115.67945)
		(size 0.6096)
		(drill 0.3048)
		(layers "F.Cu" "B.Cu")
		(locked yes)
		(tenting
			(front yes)
			(back no)
		)
		(net "GND")
	)
	(via
		(at 122.39975 90.27945)
		(size 0.6096)
		(drill 0.3048)
		(layers "F.Cu" "B.Cu")
		(locked yes)
		(tenting
			(front yes)
			(back no)
		)
		(net "GND")
	)
	(via
		(at 131.61808 101.68711)
		(size 0.6096)
		(drill 0.3048)
		(layers "F.Cu" "B.Cu")
		(locked yes)
		(tenting
			(front yes)
			(back no)
		)
		(net "GND")
	)
	(via
		(at 142.71975 90.27945)
		(size 0.6096)
		(drill 0.3048)
		(layers "F.Cu" "B.Cu")
		(locked yes)
		(tenting
			(front yes)
			(back no)
		)
		(net "GND")
	)
	(via
		(at 135.09975 118.21945)
		(size 0.6096)
		(drill 0.3048)
		(layers "F.Cu" "B.Cu")
		(locked yes)
		(tenting
			(front yes)
			(back no)
		)
		(net "GND")
	)
	(via
		(at 165.57975 92.81945)
		(size 0.6096)
		(drill 0.3048)
		(layers "F.Cu" "B.Cu")
		(locked yes)
		(tenting
			(front yes)
			(back no)
		)
		(net "GND")
	)
	(via
		(at 163.03975 110.59945)
		(size 0.6096)
		(drill 0.3048)
		(layers "F.Cu" "B.Cu")
		(locked yes)
		(tenting
			(front yes)
			(back no)
		)
		(net "GND")
	)
	(via
		(at 117.31975 110.59945)
		(size 0.6096)
		(drill 0.3048)
		(layers "F.Cu" "B.Cu")
		(locked yes)
		(tenting
			(front yes)
			(back no)
		)
		(net "GND")
	)
	(via
		(at 146.754 113.5101)
		(size 0.6096)
		(drill 0.3048)
		(layers "F.Cu" "B.Cu")
		(locked yes)
		(tenting
			(front yes)
			(back no)
		)
		(net "GND")
	)
	(via
		(at 175.73975 118.21945)
		(size 0.6096)
		(drill 0.3048)
		(layers "F.Cu" "B.Cu")
		(locked yes)
		(tenting
			(front yes)
			(back no)
		)
		(net "GND")
	)
	(via
		(at 180.81975 97.89945)
		(size 0.6096)
		(drill 0.3048)
		(layers "F.Cu" "B.Cu")
		(locked yes)
		(tenting
			(front yes)
			(back no)
		)
		(net "GND")
	)
	(via
		(at 169.6267 108.8873)
		(size 0.6096)
		(drill 0.3048)
		(layers "F.Cu" "B.Cu")
		(locked yes)
		(tenting
			(front yes)
			(back no)
		)
		(net "GND")
	)
	(via
		(at 173.19975 92.81945)
		(size 0.6096)
		(drill 0.3048)
		(layers "F.Cu" "B.Cu")
		(locked yes)
		(tenting
			(front yes)
			(back no)
		)
		(net "GND")
	)
	(via
		(at 152.87975 115.67945)
		(size 0.6096)
		(drill 0.3048)
		(layers "F.Cu" "B.Cu")
		(locked yes)
		(tenting
			(front yes)
			(back no)
		)
		(net "GND")
	)
	(via
		(at 135.09975 95.35945)
		(size 0.6096)
		(drill 0.3048)
		(layers "F.Cu" "B.Cu")
		(locked yes)
		(tenting
			(front yes)
			(back no)
		)
		(net "GND")
	)
	(via
		(at 121.85819 101.8482)
		(size 0.6096)
		(drill 0.3048)
		(layers "F.Cu" "B.Cu")
		(locked yes)
		(tenting
			(front yes)
			(back no)
		)
		(net "GND")
	)
	(via
		(at 135.04005 100.36477)
		(size 0.6096)
		(drill 0.3048)
		(layers "F.Cu" "B.Cu")
		(locked yes)
		(tenting
			(front yes)
			(back no)
		)
		(net "GND")
	)
	(via
		(at 146.7286 100.8609)
		(size 0.6096)
		(drill 0.3048)
		(layers "F.Cu" "B.Cu")
		(locked yes)
		(tenting
			(front yes)
			(back no)
		)
		(net "GND")
	)
	(via
		(at 150.9577 111.4019)
		(size 0.6096)
		(drill 0.3048)
		(layers "F.Cu" "B.Cu")
		(locked yes)
		(tenting
			(front yes)
			(back no)
		)
		(net "GND")
	)
	(via
		(at 178.27975 115.67945)
		(size 0.6096)
		(drill 0.3048)
		(layers "F.Cu" "B.Cu")
		(locked yes)
		(tenting
			(front yes)
			(back no)
		)
		(net "GND")
	)
	(via
		(at 135.09975 97.89945)
		(size 0.6096)
		(drill 0.3048)
		(layers "F.Cu" "B.Cu")
		(locked yes)
		(tenting
			(front yes)
			(back no)
		)
		(net "GND")
	)
	(via
		(at 155.41975 100.43945)
		(size 0.6096)
		(drill 0.3048)
		(layers "F.Cu" "B.Cu")
		(locked yes)
		(tenting
			(front yes)
			(back no)
		)
		(net "GND")
	)
	(via
		(at 157.95975 108.05945)
		(size 0.6096)
		(drill 0.3048)
		(layers "F.Cu" "B.Cu")
		(locked yes)
		(tenting
			(front yes)
			(back no)
		)
		(net "GND")
	)
	(via
		(at 150.9831 113.5101)
		(size 0.6096)
		(drill 0.3048)
		(layers "F.Cu" "B.Cu")
		(locked yes)
		(tenting
			(front yes)
			(back no)
		)
		(net "GND")
	)
	(via
		(at 170.65975 90.27945)
		(size 0.6096)
		(drill 0.3048)
		(layers "F.Cu" "B.Cu")
		(locked yes)
		(tenting
			(front yes)
			(back no)
		)
		(net "GND")
	)
	(via
		(at 130.01975 95.35945)
		(size 0.6096)
		(drill 0.3048)
		(layers "F.Cu" "B.Cu")
		(locked yes)
		(tenting
			(front yes)
			(back no)
		)
		(net "GND")
	)
	(via
		(at 150.9831 107.1347)
		(size 0.6096)
		(drill 0.3048)
		(layers "F.Cu" "B.Cu")
		(locked yes)
		(tenting
			(front yes)
			(back no)
		)
		(net "GND")
	)
	(via
		(at 142.4995 111.4019)
		(size 0.6096)
		(drill 0.3048)
		(layers "F.Cu" "B.Cu")
		(locked yes)
		(tenting
			(front yes)
			(back no)
		)
		(net "GND")
	)
	(via
		(at 170.65975 97.89945)
		(size 0.6096)
		(drill 0.3048)
		(layers "F.Cu" "B.Cu")
		(locked yes)
		(tenting
			(front yes)
			(back no)
		)
		(net "GND")
	)
	(via
		(at 128.6021 100.46527)
		(size 0.6096)
		(drill 0.3048)
		(layers "F.Cu" "B.Cu")
		(locked yes)
		(tenting
			(front yes)
			(back no)
		)
		(net "GND")
	)
	(via
		(at 124.93975 118.21945)
		(size 0.6096)
		(drill 0.3048)
		(layers "F.Cu" "B.Cu")
		(locked yes)
		(tenting
			(front yes)
			(back no)
		)
		(net "GND")
	)
	(via
		(at 150.9831 109.2683)
		(size 0.6096)
		(drill 0.3048)
		(layers "F.Cu" "B.Cu")
		(locked yes)
		(tenting
			(front yes)
			(back no)
		)
		(net "GND")
	)
	(via
		(at 124.93975 115.67945)
		(size 0.6096)
		(drill 0.3048)
		(layers "F.Cu" "B.Cu")
		(locked yes)
		(tenting
			(front yes)
			(back no)
		)
		(net "GND")
	)
	(via
		(at 122.39975 102.97945)
		(size 0.6096)
		(drill 0.3048)
		(layers "F.Cu" "B.Cu")
		(locked yes)
		(tenting
			(front yes)
			(back no)
		)
		(net "GND")
	)
	(via
		(at 160.49975 97.89945)
		(size 0.6096)
		(drill 0.3048)
		(layers "F.Cu" "B.Cu")
		(locked yes)
		(tenting
			(front yes)
			(back no)
		)
		(net "GND")
	)
	(via
		(at 119.85975 108.05945)
		(size 0.6096)
		(drill 0.3048)
		(layers "F.Cu" "B.Cu")
		(locked yes)
		(tenting
			(front yes)
			(back no)
		)
		(net "GND")
	)
	(via
		(at 135.09975 90.27945)
		(size 0.6096)
		(drill 0.3048)
		(layers "F.Cu" "B.Cu")
		(locked yes)
		(tenting
			(front yes)
			(back no)
		)
		(net "GND")
	)
	(via
		(at 180.81975 110.59945)
		(size 0.6096)
		(drill 0.3048)
		(layers "F.Cu" "B.Cu")
		(locked yes)
		(tenting
			(front yes)
			(back no)
		)
		(net "GND")
	)
	(via
		(at 127.0055 101.7753)
		(size 0.6096)
		(drill 0.3048)
		(layers "F.Cu" "B.Cu")
		(locked yes)
		(tenting
			(front yes)
			(back no)
		)
		(net "GND")
	)
	(via
		(at 130.8373 100.46527)
		(size 0.6096)
		(drill 0.3048)
		(layers "F.Cu" "B.Cu")
		(locked yes)
		(tenting
			(front yes)
			(back no)
		)
		(net "GND")
	)
	(via
		(at 137.46795 101.77661)
		(size 0.6096)
		(drill 0.3048)
		(layers "F.Cu" "B.Cu")
		(locked yes)
		(tenting
			(front yes)
			(back no)
		)
		(net "GND")
	)
	(via
		(at 163.03975 100.43945)
		(size 0.6096)
		(drill 0.3048)
		(layers "F.Cu" "B.Cu")
		(locked yes)
		(tenting
			(front yes)
			(back no)
		)
		(net "GND")
	)
	(via
		(at 168.11975 95.35945)
		(size 0.6096)
		(drill 0.3048)
		(layers "F.Cu" "B.Cu")
		(locked yes)
		(tenting
			(front yes)
			(back no)
		)
		(net "GND")
	)
	(via
		(at 180.81975 102.97945)
		(size 0.6096)
		(drill 0.3048)
		(layers "F.Cu" "B.Cu")
		(locked yes)
		(tenting
			(front yes)
			(back no)
		)
		(net "GND")
	)
	(via
		(at 165.57975 113.13945)
		(size 0.6096)
		(drill 0.3048)
		(layers "F.Cu" "B.Cu")
		(locked yes)
		(tenting
			(front yes)
			(back no)
		)
		(net "GND")
	)
	(via
		(at 137.25898 100.55478)
		(size 0.6096)
		(drill 0.3048)
		(layers "F.Cu" "B.Cu")
		(locked yes)
		(tenting
			(front yes)
			(back no)
		)
		(net "GND")
	)
	(via
		(at 175.73975 97.89945)
		(size 0.6096)
		(drill 0.3048)
		(layers "F.Cu" "B.Cu")
		(locked yes)
		(tenting
			(front yes)
			(back no)
		)
		(net "GND")
	)
	(via
		(at 124.93975 105.51945)
		(size 0.6096)
		(drill 0.3048)
		(layers "F.Cu" "B.Cu")
		(locked yes)
		(tenting
			(front yes)
			(back no)
		)
		(net "GND")
	)
	(via
		(at 157.95975 100.43945)
		(size 0.6096)
		(drill 0.3048)
		(layers "F.Cu" "B.Cu")
		(locked yes)
		(tenting
			(front yes)
			(back no)
		)
		(net "GND")
	)
	(via
		(at 124.93975 108.05945)
		(size 0.6096)
		(drill 0.3048)
		(layers "F.Cu" "B.Cu")
		(locked yes)
		(tenting
			(front yes)
			(back no)
		)
		(net "GND")
	)
	(via
		(at 130.01975 92.81945)
		(size 0.6096)
		(drill 0.3048)
		(layers "F.Cu" "B.Cu")
		(locked yes)
		(tenting
			(front yes)
			(back no)
		)
		(net "GND")
	)
	(via
		(at 117.31975 97.89945)
		(size 0.6096)
		(drill 0.3048)
		(layers "F.Cu" "B.Cu")
		(locked yes)
		(tenting
			(front yes)
			(back no)
		)
		(net "GND")
	)
	(via
		(at 130.01975 90.27945)
		(size 0.6096)
		(drill 0.3048)
		(layers "F.Cu" "B.Cu")
		(locked yes)
		(tenting
			(front yes)
			(back no)
		)
		(net "GND")
	)
	(via
		(at 155.41975 110.59945)
		(size 0.6096)
		(drill 0.3048)
		(layers "F.Cu" "B.Cu")
		(locked yes)
		(tenting
			(front yes)
			(back no)
		)
		(net "GND")
	)
	(via
		(at 145.25975 92.81945)
		(size 0.6096)
		(drill 0.3048)
		(layers "F.Cu" "B.Cu")
		(locked yes)
		(tenting
			(front yes)
			(back no)
		)
		(net "GND")
	)
	(via
		(at 124.93975 97.89945)
		(size 0.6096)
		(drill 0.3048)
		(layers "F.Cu" "B.Cu")
		(locked yes)
		(tenting
			(front yes)
			(back no)
		)
		(net "GND")
	)
	(via
		(at 119.85975 92.81945)
		(size 0.6096)
		(drill 0.3048)
		(layers "F.Cu" "B.Cu")
		(locked yes)
		(tenting
			(front yes)
			(back no)
		)
		(net "GND")
	)
	(via
		(at 146.754 107.1347)
		(size 0.6096)
		(drill 0.3048)
		(layers "F.Cu" "B.Cu")
		(locked yes)
		(tenting
			(front yes)
			(back no)
		)
		(net "GND")
	)
	(via
		(at 180.81975 115.67945)
		(size 0.6096)
		(drill 0.3048)
		(layers "F.Cu" "B.Cu")
		(locked yes)
		(tenting
			(front yes)
			(back no)
		)
		(net "GND")
	)
	(via
		(at 132.55975 110.59945)
		(size 0.6096)
		(drill 0.3048)
		(layers "F.Cu" "B.Cu")
		(locked yes)
		(tenting
			(front yes)
			(back no)
		)
		(net "GND")
	)
	(via
		(at 180.81975 100.43945)
		(size 0.6096)
		(drill 0.3048)
		(layers "F.Cu" "B.Cu")
		(locked yes)
		(tenting
			(front yes)
			(back no)
		)
		(net "GND")
	)
	(via
		(at 155.41975 113.13945)
		(size 0.6096)
		(drill 0.3048)
		(layers "F.Cu" "B.Cu")
		(locked yes)
		(tenting
			(front yes)
			(back no)
		)
		(net "GND")
	)
	(via
		(at 150.33975 90.27945)
		(size 0.6096)
		(drill 0.3048)
		(layers "F.Cu" "B.Cu")
		(locked yes)
		(tenting
			(front yes)
			(back no)
		)
		(net "GND")
	)
	(via
		(at 120.91351 102.44536)
		(size 0.6096)
		(drill 0.3048)
		(layers "F.Cu" "B.Cu")
		(locked yes)
		(tenting
			(front yes)
			(back no)
		)
		(net "GND")
	)
	(via
		(at 135.09975 115.67945)
		(size 0.6096)
		(drill 0.3048)
		(layers "F.Cu" "B.Cu")
		(locked yes)
		(tenting
			(front yes)
			(back no)
		)
		(net "GND")
	)
	(via
		(at 119.85975 115.67945)
		(size 0.6096)
		(drill 0.3048)
		(layers "F.Cu" "B.Cu")
		(locked yes)
		(tenting
			(front yes)
			(back no)
		)
		(net "GND")
	)
	(via
		(at 146.7286 102.9945)
		(size 0.6096)
		(drill 0.3048)
		(layers "F.Cu" "B.Cu")
		(locked yes)
		(tenting
			(front yes)
			(back no)
		)
		(net "GND")
	)
	(via
		(at 127.47975 92.81945)
		(size 0.6096)
		(drill 0.3048)
		(layers "F.Cu" "B.Cu")
		(locked yes)
		(tenting
			(front yes)
			(back no)
		)
		(net "GND")
	)
	(via
		(at 173.19975 118.21945)
		(size 0.6096)
		(drill 0.3048)
		(layers "F.Cu" "B.Cu")
		(locked yes)
		(tenting
			(front yes)
			(back no)
		)
		(net "GND")
	)
	(via
		(at 117.31975 95.35945)
		(size 0.6096)
		(drill 0.3048)
		(layers "F.Cu" "B.Cu")
		(locked yes)
		(tenting
			(front yes)
			(back no)
		)
		(net "GND")
	)
	(arc
		(start 119.063833 99.85699)
		(mid 120.70528 99.03149)
		(end 122.346727 99.85699)
		(width 0.0127)
		(layer "F.Cu")
		(net "GND")
	)
	(arc
		(start 122.346727 102.29539)
		(mid 120.70528 103.12089)
		(end 119.063833 102.29539)
		(width 0.0127)
		(layer "F.Cu")
		(net "GND")
	)
	(segment
		(start 138.9597 105.8425)
		(end 139.25811 105.5441)
		(width 0.2032)
		(layer "F.Cu")
		(net "ANT_SHORT_N")
	)
	(segment
		(start 136.3271 106.8179)
		(end 136.4487 106.8179)
		(width 0.2032)
		(layer "F.Cu")
		(net "ANT_SHORT_N")
	)
	(segment
		(start 138.55049 105.8425)
		(end 138.9597 105.8425)
		(width 0.2032)
		(layer "F.Cu")
		(net "ANT_SHORT_N")
	)
	(segment
		(start 136.4487 106.8179)
		(end 136.4971 106.8663)
		(width 0.2032)
		(layer "F.Cu")
		(net "ANT_SHORT_N")
	)
	(segment
		(start 136.4487 106.8179)
		(end 137.5751 106.8179)
		(width 0.2032)
		(layer "F.Cu")
		(net "ANT_SHORT_N")
	)
	(segment
		(start 136.4971 108.6333)
		(end 136.4971 106.8663)
		(width 0.2032)
		(layer "F.Cu")
		(net "ANT_SHORT_N")
	)
	(segment
		(start 137.5751 106.8179)
		(end 138.55049 105.8425)
		(width 0.2032)
		(layer "F.Cu")
		(net "ANT_SHORT_N")
	)
	(segment
		(start 138.33373 104.69438)
		(end 139.00783 104.69438)
		(width 0.2032)
		(layer "F.Cu")
		(net "ANT_OFF")
	)
	(segment
		(start 136.3755 106.2695)
		(end 136.69694 106.2695)
		(width 0.2032)
		(layer "F.Cu")
		(net "ANT_OFF")
	)
	(segment
		(start 136.80621 106.2219)
		(end 138.33373 104.69438)
		(width 0.2032)
		(layer "F.Cu")
		(net "ANT_OFF")
	)
	(segment
		(start 136.3271 106.3179)
		(end 136.3755 106.2695)
		(width 0.2032)
		(layer "F.Cu")
		(net "ANT_OFF")
	)
	(segment
		(start 136.69694 106.2695)
		(end 136.74454 106.2219)
		(width 0.2032)
		(layer "F.Cu")
		(net "ANT_OFF")
	)
	(segment
		(start 136.74454 106.2219)
		(end 136.80621 106.2219)
		(width 0.2032)
		(layer "F.Cu")
		(net "ANT_OFF")
	)
	(segment
		(start 139.00783 104.69438)
		(end 139.25811 104.4441)
		(width 0.2032)
		(layer "F.Cu")
		(net "ANT_OFF")
	)
	(segment
		(start 136.69694 105.7695)
		(end 136.74454 105.7219)
		(width 0.2032)
		(layer "F.Cu")
		(net "ANT_DET")
	)
	(segment
		(start 136.5225 104.63308)
		(end 136.98111 105.09169)
		(width 0.2032)
		(layer "F.Cu")
		(net "ANT_DET")
	)
	(segment
		(start 136.80332 105.7219)
		(end 136.98111 105.54411)
		(width 0.2032)
		(layer "F.Cu")
		(net "ANT_DET")
	)
	(segment
		(start 136.98111 105.54411)
		(end 136.98111 105.09169)
		(width 0.2032)
		(layer "F.Cu")
		(net "ANT_DET")
	)
	(segment
		(start 136.5225 104.63308)
		(end 136.5225 103.2739)
		(width 0.2032)
		(layer "F.Cu")
		(net "ANT_DET")
	)
	(segment
		(start 136.3755 105.7695)
		(end 136.69694 105.7695)
		(width 0.2032)
		(layer "F.Cu")
		(net "ANT_DET")
	)
	(segment
		(start 136.5225 103.2739)
		(end 139.18791 103.2739)
		(width 0.2032)
		(layer "F.Cu")
		(net "ANT_DET")
	)
	(segment
		(start 136.3271 105.8179)
		(end 136.3755 105.7695)
		(width 0.2032)
		(layer "F.Cu")
		(net "ANT_DET")
	)
	(segment
		(start 139.18791 103.2739)
		(end 139.25811 103.3441)
		(width 0.2032)
		(layer "F.Cu")
		(net "ANT_DET")
	)
	(segment
		(start 136.74454 105.7219)
		(end 136.80332 105.7219)
		(width 0.2032)
		(layer "F.Cu")
		(net "ANT_DET")
	)
	(zone
		(layer "F.Cu")
		(hatch edge 0.5)
		(connect_pads
			(clearance 0)
		)
		(min_thickness 0.25)
		(keepout
			(tracks allowed)
			(vias allowed)
			(pads allowed)
			(copperpour not_allowed)
			(footprints allowed)
		)
		(placement
			(enabled no)
			(sheetname "")
		)
		(fill
			(thermal_gap 0.5)
			(thermal_bridge_width 0.5)
			(island_removal_mode 0)
		)
		(polygon
			(pts
				(xy 140.08416 100.56049) (xy 140.14863 100.60357) (xy 140.19171 100.66805) (xy 140.20684 100.7441)
				(xy 140.20684 101.5441) (xy 140.19171 101.62015) (xy 140.14863 101.68463) (xy 140.08416 101.72771)
				(xy 140.0081 101.74284) (xy 138.50811 101.74284) (xy 138.43206 101.72771) (xy 138.36758 101.68463)
				(xy 138.3245 101.62015) (xy 138.30937 101.5441) (xy 138.30937 101.46066) (xy 135.27934 101.46066)
				(xy 135.26595 101.52799) (xy 135.22286 101.59246) (xy 135.15839 101.63554) (xy 135.08234 101.65067)
				(xy 134.46699 101.65067) (xy 134.39094 101.63554) (xy 134.32646 101.59246) (xy 134.28338 101.52799)
				(xy 134.26825 101.45193) (xy 134.26825 100.87946) (xy 134.28338 100.80341) (xy 134.32646 100.73894)
				(xy 134.39094 100.69585) (xy 134.46699 100.68073) (xy 135.08234 100.68073) (xy 135.15839 100.69585)
				(xy 135.22286 100.73894) (xy 135.26595 100.80341) (xy 135.27934 100.87074) (xy 138.30937 100.87074)
				(xy 138.30937 100.7441) (xy 138.3245 100.66805) (xy 138.36758 100.60357) (xy 138.43206 100.56049)
				(xy 138.50811 100.54536) (xy 140.0081 100.54536)
			)
		)
	)
	(zone
		(net "VCC")
		(layer "F.Cu")
		(hatch edge 0.5)
		(priority 1)
		(connect_pads
			(clearance 0.5)
		)
		(min_thickness 0.25)
		(fill yes
			(thermal_gap 0.254)
			(thermal_bridge_width 0.254)
			(island_removal_mode 0)
		)
		(polygon
			(pts
				(xy 153.3673 105.10254) (xy 155.1453 105.10254) (xy 155.1453 103.83254) (xy 156.2883 103.83254)
				(xy 156.2883 109.42054) (xy 156.69471 109.82696) (xy 155.0183 109.29109) (xy 153.3673 109.29109)
				(xy 153.3673 107.26154) (xy 155.0183 107.26154) (xy 155.0183 105.99154) (xy 153.3673 105.99154)
			)
		)
	)
	(zone
		(layer "F.Cu")
		(hatch edge 0.5)
		(connect_pads
			(clearance 0)
		)
		(min_thickness 0.25)
		(keepout
			(tracks allowed)
			(vias allowed)
			(pads allowed)
			(copperpour not_allowed)
			(footprints allowed)
		)
		(placement
			(enabled no)
			(sheetname "")
		)
		(fill
			(thermal_gap 0.5)
			(thermal_bridge_width 0.5)
			(island_removal_mode 0)
		)
		(polygon
			(pts
				(xy 120.95832 100.03159) (xy 120.98294 100.03995) (xy 121.00843 100.04502) (xy 121.22006 100.13268)
				(xy 121.24166 100.14712) (xy 121.26499 100.15862) (xy 121.44671 100.29807) (xy 121.46386 100.31762)
				(xy 121.4834 100.33475) (xy 121.62285 100.51648) (xy 121.63434 100.53979) (xy 121.64878 100.56141)
				(xy 121.73644 100.77304) (xy 121.73807 100.78123) (xy 125.35911 100.78123) (xy 125.37157 100.76257)
				(xy 125.43605 100.71949) (xy 125.5121 100.70436) (xy 126.1621 100.70436) (xy 126.23816 100.71949)
				(xy 126.30263 100.76257) (xy 126.3151 100.78123) (xy 127.63086 100.78123) (xy 127.63381 100.77925)
				(xy 127.70987 100.76412) (xy 128.28234 100.76412) (xy 128.35839 100.77925) (xy 128.36134 100.78123)
				(xy 133.44108 100.78123) (xy 133.46934 100.73894) (xy 133.53381 100.69585) (xy 133.60987 100.68073)
				(xy 134.22521 100.68073) (xy 134.30126 100.69585) (xy 134.36574 100.73894) (xy 134.40882 100.80341)
				(xy 134.42395 100.87946) (xy 134.42395 101.45193) (xy 134.40882 101.52799) (xy 134.36574 101.59246)
				(xy 134.30126 101.63554) (xy 134.22521 101.65067) (xy 133.60987 101.65067) (xy 133.53381 101.63554)
				(xy 133.46934 101.59246) (xy 133.42626 101.52799) (xy 133.41113 101.45193) (xy 133.41113 101.37115)
				(xy 128.48107 101.37115) (xy 128.48107 101.57821) (xy 128.46595 101.65426) (xy 128.42287 101.71874)
				(xy 128.35839 101.76182) (xy 128.28234 101.77694) (xy 127.70987 101.77694) (xy 127.63381 101.76182)
				(xy 127.56934 101.71874) (xy 127.52626 101.65426) (xy 127.51113 101.57821) (xy 127.51113 101.37115)
				(xy 126.36084 101.37115) (xy 126.36084 101.7531) (xy 126.34571 101.82915) (xy 126.30263 101.89363)
				(xy 126.23816 101.93671) (xy 126.1621 101.95184) (xy 125.5121 101.95184) (xy 125.43605 101.93671)
				(xy 125.37157 101.89363) (xy 125.32849 101.82915) (xy 125.31336 101.7531) (xy 125.31336 101.37115)
				(xy 121.73807 101.37115) (xy 121.73644 101.37934) (xy 121.64878 101.59097) (xy 121.63434 101.61258)
				(xy 121.62284 101.6359) (xy 121.4834 101.81763) (xy 121.46385 101.83477) (xy 121.44672 101.85431)
				(xy 121.26499 101.99376) (xy 121.24167 102.00526) (xy 121.22006 102.0197) (xy 121.00843 102.10736)
				(xy 120.98294 102.11243) (xy 120.95832 102.12078) (xy 120.73122 102.15068) (xy 120.70528 102.14898)
				(xy 120.67934 102.15068) (xy 120.45223 102.12078) (xy 120.42761 102.11243) (xy 120.40212 102.10736)
				(xy 120.19049 102.0197) (xy 120.16889 102.00526) (xy 120.14556 101.99376) (xy 119.96384 101.85431)
				(xy 119.94669 101.83476) (xy 119.92715 101.81763) (xy 119.78771 101.6359) (xy 119.77621 101.61258)
				(xy 119.76177 101.59097) (xy 119.67411 101.37934) (xy 119.66904 101.35385) (xy 119.66068 101.32923)
				(xy 119.63078 101.10213) (xy 119.63248 101.07619) (xy 119.63078 101.05025) (xy 119.66068 100.82315)
				(xy 119.66904 100.79853) (xy 119.67411 100.77304) (xy 119.76177 100.56141) (xy 119.77621 100.53979)
				(xy 119.78771 100.51648) (xy 119.92715 100.33475) (xy 119.9467 100.31761) (xy 119.96383 100.29807)
				(xy 120.14556 100.15862) (xy 120.16888 100.14712) (xy 120.19049 100.13268) (xy 120.40212 100.04502)
				(xy 120.42761 100.03995) (xy 120.45223 100.03159) (xy 120.67933 100.0017) (xy 120.70528 100.00339)
				(xy 120.73121 100.0017)
			)
		)
	)
	(zone
		(net "GND")
		(layer "F.Cu")
		(hatch edge 0.5)
		(priority 7)
		(connect_pads
			(clearance 0.5)
		)
		(min_thickness 0.25)
		(fill yes
			(thermal_gap 0.254)
			(thermal_bridge_width 0.254)
			(island_removal_mode 0)
		)
		(polygon
			(pts
				(xy 114.4071 88.7451) (xy 182.4791 88.7451) (xy 182.4791 121.2571) (xy 114.4071 121.2571)
			)
		)
	)
	(zone
		(layers "F.Cu" "B.Cu" "In1.Cu" "In2.Cu")
		(hatch edge 0.5)
		(connect_pads
			(clearance 0)
		)
		(min_thickness 0.25)
		(keepout
			(tracks not_allowed)
			(vias not_allowed)
			(pads not_allowed)
			(copperpour not_allowed)
			(footprints allowed)
		)
		(placement
			(enabled no)
			(sheetname "")
		)
		(fill
			(thermal_gap 0.5)
			(thermal_bridge_width 0.5)
			(island_removal_mode 0)
		)
		(polygon
			(pts
				(xy 115.960101 120.86975) (xy 115.963833 120.870963) (xy 115.96614 120.874138) (xy 115.96614 120.878062)
				(xy 115.963833 120.881237) (xy 115.960101 120.88245) (xy 115.777536 120.866478) (xy 115.600517 120.819046)
				(xy 115.434425 120.741596) (xy 115.284305 120.636481) (xy 115.154719 120.506895) (xy 115.049604 120.356775)
				(xy 114.972154 120.190683) (xy 114.924722 120.013664) (xy 114.90875 119.831099) (xy 114.909963 119.827367)
				(xy 114.913138 119.82506) (xy 114.917062 119.82506) (xy 114.920237 119.827367) (xy 114.92145 119.831099)
				(xy 114.92145 119.921969) (xy 114.953009 120.100949) (xy 115.015168 120.271729) (xy 115.106038 120.429121)
				(xy 115.222858 120.568342) (xy 115.362079 120.685162) (xy 115.519471 120.776032) (xy 115.690251 120.838191)
				(xy 115.869231 120.86975) (xy 115.960101 120.86975)
			)
		)
	)
	(zone
		(layers "F.Cu" "B.Cu" "In1.Cu" "In2.Cu")
		(hatch edge 0.5)
		(connect_pads
			(clearance 0)
		)
		(min_thickness 0.25)
		(keepout
			(tracks not_allowed)
			(vias not_allowed)
			(pads not_allowed)
			(copperpour not_allowed)
			(footprints allowed)
		)
		(placement
			(enabled no)
			(sheetname "")
		)
		(fill
			(thermal_gap 0.5)
			(thermal_bridge_width 0.5)
			(island_removal_mode 0)
		)
		(polygon
			(pts
				(xy 182.07975 119.8611) (xy 182.080963 119.857368) (xy 182.084138 119.855061) (xy 182.088062 119.855061)
				(xy 182.091237 119.857368) (xy 182.09245 119.8611) (xy 182.076892 120.03904) (xy 182.030691 120.21158)
				(xy 181.955247 120.373484) (xy 181.852852 120.51984) (xy 181.726611 120.646204) (xy 181.580357 120.748744)
				(xy 181.418527 120.824346) (xy 181.246032 120.870717) (xy 181.068107 120.88645) (xy 181.064374 120.885241)
				(xy 181.062064 120.882068) (xy 181.06206 120.878144) (xy 181.064364 120.874966) (xy 181.068095 120.87375)
				(xy 181.156635 120.873668) (xy 181.330998 120.842766) (xy 181.497353 120.782074) (xy 181.650651 120.693433)
				(xy 181.78624 120.579534) (xy 181.900006 120.443833) (xy 181.988496 120.290448) (xy 182.049024 120.124034)
				(xy 182.079755 119.94964) (xy 182.07975 119.8611)
			)
		)
	)
	(zone
		(layers "F.Cu" "B.Cu" "In1.Cu" "In2.Cu")
		(hatch edge 0.5)
		(connect_pads
			(clearance 0)
		)
		(min_thickness 0.25)
		(keepout
			(tracks not_allowed)
			(vias not_allowed)
			(pads not_allowed)
			(copperpour not_allowed)
			(footprints allowed)
		)
		(placement
			(enabled no)
			(sheetname "")
		)
		(fill
			(thermal_gap 0.5)
			(thermal_bridge_width 0.5)
			(island_removal_mode 0)
		)
		(polygon
			(pts
				(xy 181.07053 120.874233) (xy 181.073967 120.87767) (xy 181.073967 120.88253) (xy 181.07053 120.885967)
				(xy 181.068099 120.88645) (xy 115.9601 120.88245) (xy 115.95767 120.881967) (xy 115.954233 120.87853)
				(xy 115.954233 120.87367) (xy 115.95767 120.870233) (xy 115.9601 120.86975) (xy 181.0681 120.87375)
			)
		)
	)
	(zone
		(layers "F.Cu" "B.Cu" "In1.Cu" "In2.Cu")
		(hatch edge 0.5)
		(connect_pads
			(clearance 0)
		)
		(min_thickness 0.25)
		(keepout
			(tracks not_allowed)
			(vias not_allowed)
			(pads not_allowed)
			(copperpour not_allowed)
			(footprints allowed)
		)
		(placement
			(enabled no)
			(sheetname "")
		)
		(fill
			(thermal_gap 0.5)
			(thermal_bridge_width 0.5)
			(island_removal_mode 0)
		)
		(polygon
			(pts
				(xy 181.0091 89.13345) (xy 181.005368 89.132237) (xy 181.003061 89.129062) (xy 181.003061 89.125138)
				(xy 181.005368 89.121963) (xy 181.0091 89.12075) (xy 181.197632 89.137235) (xy 181.380443 89.186189)
				(xy 181.551984 89.266126) (xy 181.707049 89.37462) (xy 181.840933 89.50838) (xy 181.949571 89.663344)
				(xy 182.029667 89.834811) (xy 182.07879 90.017576) (xy 182.09545 90.206093) (xy 182.094241 90.209827)
				(xy 182.091068 90.212136) (xy 182.087143 90.21214) (xy 182.083966 90.209836) (xy 182.08275 90.206105)
				(xy 182.082668 90.112228) (xy 182.049912 89.927354) (xy 181.985569 89.750969) (xy 181.891592 89.588428)
				(xy 181.770832 89.444662) (xy 181.626954 89.324036) (xy 181.464326 89.230209) (xy 181.287882 89.16603)
				(xy 181.102977 89.133445) (xy 181.0091 89.13345)
			)
		)
	)
	(zone
		(layers "F.Cu" "B.Cu" "In1.Cu" "In2.Cu")
		(hatch edge 0.5)
		(connect_pads
			(clearance 0)
		)
		(min_thickness 0.25)
		(keepout
			(tracks not_allowed)
			(vias not_allowed)
			(pads not_allowed)
			(copperpour not_allowed)
			(footprints allowed)
		)
		(placement
			(enabled no)
			(sheetname "")
		)
		(fill
			(thermal_gap 0.5)
			(thermal_bridge_width 0.5)
			(island_removal_mode 0)
		)
		(polygon
			(pts
				(xy 181.01153 89.121233) (xy 181.014967 89.12467) (xy 181.014967 89.12953) (xy 181.01153 89.132967)
				(xy 181.0091 89.13345) (xy 115.9831 89.13545) (xy 115.98067 89.134967) (xy 115.977233 89.13153)
				(xy 115.977233 89.12667) (xy 115.98067 89.123233) (xy 115.9831 89.12275) (xy 181.0091 89.12075)
			)
		)
	)
	(zone
		(layers "F.Cu" "B.Cu" "In1.Cu" "In2.Cu")
		(hatch edge 0.5)
		(connect_pads
			(clearance 0)
		)
		(min_thickness 0.25)
		(keepout
			(tracks not_allowed)
			(vias not_allowed)
			(pads not_allowed)
			(copperpour not_allowed)
			(footprints allowed)
		)
		(placement
			(enabled no)
			(sheetname "")
		)
		(fill
			(thermal_gap 0.5)
			(thermal_bridge_width 0.5)
			(island_removal_mode 0)
		)
		(polygon
			(pts
				(xy 178.629423 116.466752) (xy 178.861689 116.54222) (xy 179.079291 116.653093) (xy 179.276868 116.796642)
				(xy 179.449558 116.969332) (xy 179.593107 117.166909) (xy 179.70398 117.384511) (xy 179.779448 117.616777)
				(xy 179.817652 117.85799) (xy 179.817652 118.10221) (xy 179.779448 118.343423) (xy 179.70398 118.575689)
				(xy 179.593107 118.793291) (xy 179.449558 118.990868) (xy 179.276868 119.163558) (xy 179.079291 119.307107)
				(xy 178.861689 119.41798) (xy 178.629423 119.493448) (xy 178.38821 119.531652) (xy 178.14399 119.531652)
				(xy 177.902777 119.493448) (xy 177.670511 119.41798) (xy 177.452909 119.307107) (xy 177.255332 119.163558)
				(xy 177.082642 118.990868) (xy 176.939093 118.793291) (xy 176.82822 118.575689) (xy 176.752752 118.343423)
				(xy 176.714548 118.10221) (xy 176.714548 117.858612) (xy 176.72245 117.858612) (xy 176.72245 118.101588)
				(xy 176.76046 118.341572) (xy 176.835544 118.572656) (xy 176.945852 118.789149) (xy 177.08867 118.98572)
				(xy 177.26048 119.15753) (xy 177.457051 119.300348) (xy 177.673544 119.410656) (xy 177.904628 119.48574)
				(xy 178.144612 119.52375) (xy 178.387588 119.52375) (xy 178.627572 119.48574) (xy 178.858656 119.410656)
				(xy 179.075149 119.300348) (xy 179.27172 119.15753) (xy 179.44353 118.98572) (xy 179.586348 118.789149)
				(xy 179.696656 118.572656) (xy 179.77174 118.341572) (xy 179.80975 118.101588) (xy 179.80975 117.858612)
				(xy 179.77174 117.618628) (xy 179.696656 117.387544) (xy 179.586348 117.171051) (xy 179.44353 116.97448)
				(xy 179.27172 116.80267) (xy 179.075149 116.659852) (xy 178.858656 116.549544) (xy 178.627572 116.47446)
				(xy 178.387588 116.43645) (xy 178.144612 116.43645) (xy 177.904628 116.47446) (xy 177.673544 116.549544)
				(xy 177.457051 116.659852) (xy 177.26048 116.80267) (xy 177.08867 116.97448) (xy 176.945852 117.171051)
				(xy 176.835544 117.387544) (xy 176.76046 117.618628) (xy 176.72245 117.858612) (xy 176.714548 117.858612)
				(xy 176.714548 117.85799) (xy 176.752752 117.616777) (xy 176.82822 117.384511) (xy 176.939093 117.166909)
				(xy 177.082642 116.969332) (xy 177.255332 116.796642) (xy 177.452909 116.653093) (xy 177.670511 116.54222)
				(xy 177.902777 116.466752) (xy 178.14399 116.428548) (xy 178.38821 116.428548)
			)
		)
	)
	(zone
		(layers "F.Cu" "B.Cu" "In1.Cu" "In2.Cu")
		(hatch edge 0.5)
		(connect_pads
			(clearance 0)
		)
		(min_thickness 0.25)
		(keepout
			(tracks not_allowed)
			(vias not_allowed)
			(pads not_allowed)
			(copperpour not_allowed)
			(footprints allowed)
		)
		(placement
			(enabled no)
			(sheetname "")
		)
		(fill
			(thermal_gap 0.5)
			(thermal_bridge_width 0.5)
			(island_removal_mode 0)
		)
		(polygon
			(pts
				(xy 114.920967 119.83353) (xy 114.91753 119.836967) (xy 114.91267 119.836967) (xy 114.909233 119.83353)
				(xy 114.90875 119.8311) (xy 114.90675 90.2001) (xy 114.907233 90.19767) (xy 114.91067 90.194233)
				(xy 114.91553 90.194233) (xy 114.918967 90.19767) (xy 114.91945 90.2001) (xy 114.92145 119.8311)
			)
		)
	)
	(zone
		(layers "F.Cu" "B.Cu" "In1.Cu" "In2.Cu")
		(hatch edge 0.5)
		(connect_pads
			(clearance 0)
		)
		(min_thickness 0.25)
		(keepout
			(tracks not_allowed)
			(vias not_allowed)
			(pads not_allowed)
			(copperpour not_allowed)
			(footprints allowed)
		)
		(placement
			(enabled no)
			(sheetname "")
		)
		(fill
			(thermal_gap 0.5)
			(thermal_bridge_width 0.5)
			(island_removal_mode 0)
		)
		(polygon
			(pts
				(xy 178.629423 90.466752) (xy 178.861689 90.54222) (xy 179.079291 90.653093) (xy 179.276868 90.796642)
				(xy 179.449558 90.969332) (xy 179.593107 91.166909) (xy 179.70398 91.384511) (xy 179.779448 91.616777)
				(xy 179.817652 91.85799) (xy 179.817652 92.10221) (xy 179.779448 92.343423) (xy 179.70398 92.575689)
				(xy 179.593107 92.793291) (xy 179.449558 92.990868) (xy 179.276868 93.163558) (xy 179.079291 93.307107)
				(xy 178.861689 93.41798) (xy 178.629423 93.493448) (xy 178.38821 93.531652) (xy 178.14399 93.531652)
				(xy 177.902777 93.493448) (xy 177.670511 93.41798) (xy 177.452909 93.307107) (xy 177.255332 93.163558)
				(xy 177.082642 92.990868) (xy 176.939093 92.793291) (xy 176.82822 92.575689) (xy 176.752752 92.343423)
				(xy 176.714548 92.10221) (xy 176.714548 91.858612) (xy 176.72245 91.858612) (xy 176.72245 92.101588)
				(xy 176.76046 92.341572) (xy 176.835544 92.572656) (xy 176.945852 92.789149) (xy 177.08867 92.98572)
				(xy 177.26048 93.15753) (xy 177.457051 93.300348) (xy 177.673544 93.410656) (xy 177.904628 93.48574)
				(xy 178.144612 93.52375) (xy 178.387588 93.52375) (xy 178.627572 93.48574) (xy 178.858656 93.410656)
				(xy 179.075149 93.300348) (xy 179.27172 93.15753) (xy 179.44353 92.98572) (xy 179.586348 92.789149)
				(xy 179.696656 92.572656) (xy 179.77174 92.341572) (xy 179.80975 92.101588) (xy 179.80975 91.858612)
				(xy 179.77174 91.618628) (xy 179.696656 91.387544) (xy 179.586348 91.171051) (xy 179.44353 90.97448)
				(xy 179.27172 90.80267) (xy 179.075149 90.659852) (xy 178.858656 90.549544) (xy 178.627572 90.47446)
				(xy 178.387588 90.43645) (xy 178.144612 90.43645) (xy 177.904628 90.47446) (xy 177.673544 90.549544)
				(xy 177.457051 90.659852) (xy 177.26048 90.80267) (xy 177.08867 90.97448) (xy 176.945852 91.171051)
				(xy 176.835544 91.387544) (xy 176.76046 91.618628) (xy 176.72245 91.858612) (xy 176.714548 91.858612)
				(xy 176.714548 91.85799) (xy 176.752752 91.616777) (xy 176.82822 91.384511) (xy 176.939093 91.166909)
				(xy 177.082642 90.969332) (xy 177.255332 90.796642) (xy 177.452909 90.653093) (xy 177.670511 90.54222)
				(xy 177.902777 90.466752) (xy 178.14399 90.428548) (xy 178.38821 90.428548)
			)
		)
	)
	(zone
		(layers "F.Cu" "B.Cu" "In1.Cu" "In2.Cu")
		(hatch edge 0.5)
		(connect_pads
			(clearance 0)
		)
		(min_thickness 0.25)
		(keepout
			(tracks not_allowed)
			(vias not_allowed)
			(pads not_allowed)
			(copperpour not_allowed)
			(footprints allowed)
		)
		(placement
			(enabled no)
			(sheetname "")
		)
		(fill
			(thermal_gap 0.5)
			(thermal_bridge_width 0.5)
			(island_removal_mode 0)
		)
		(polygon
			(pts
				(xy 118.129423 116.466752) (xy 118.361689 116.54222) (xy 118.579291 116.653093) (xy 118.776868 116.796642)
				(xy 118.949558 116.969332) (xy 119.093107 117.166909) (xy 119.20398 117.384511) (xy 119.279448 117.616777)
				(xy 119.317652 117.85799) (xy 119.317652 118.10221) (xy 119.279448 118.343423) (xy 119.20398 118.575689)
				(xy 119.093107 118.793291) (xy 118.949558 118.990868) (xy 118.776868 119.163558) (xy 118.579291 119.307107)
				(xy 118.361689 119.41798) (xy 118.129423 119.493448) (xy 117.88821 119.531652) (xy 117.64399 119.531652)
				(xy 117.402777 119.493448) (xy 117.170511 119.41798) (xy 116.952909 119.307107) (xy 116.755332 119.163558)
				(xy 116.582642 118.990868) (xy 116.439093 118.793291) (xy 116.32822 118.575689) (xy 116.252752 118.343423)
				(xy 116.214548 118.10221) (xy 116.214548 117.858612) (xy 116.22245 117.858612) (xy 116.22245 118.101588)
				(xy 116.26046 118.341572) (xy 116.335544 118.572656) (xy 116.445852 118.789149) (xy 116.58867 118.98572)
				(xy 116.76048 119.15753) (xy 116.957051 119.300348) (xy 117.173544 119.410656) (xy 117.404628 119.48574)
				(xy 117.644612 119.52375) (xy 117.887588 119.52375) (xy 118.127572 119.48574) (xy 118.358656 119.410656)
				(xy 118.575149 119.300348) (xy 118.77172 119.15753) (xy 118.94353 118.98572) (xy 119.086348 118.789149)
				(xy 119.196656 118.572656) (xy 119.27174 118.341572) (xy 119.30975 118.101588) (xy 119.30975 117.858612)
				(xy 119.27174 117.618628) (xy 119.196656 117.387544) (xy 119.086348 117.171051) (xy 118.94353 116.97448)
				(xy 118.77172 116.80267) (xy 118.575149 116.659852) (xy 118.358656 116.549544) (xy 118.127572 116.47446)
				(xy 117.887588 116.43645) (xy 117.644612 116.43645) (xy 117.404628 116.47446) (xy 117.173544 116.549544)
				(xy 116.957051 116.659852) (xy 116.76048 116.80267) (xy 116.58867 116.97448) (xy 116.445852 117.171051)
				(xy 116.335544 117.387544) (xy 116.26046 117.618628) (xy 116.22245 117.858612) (xy 116.214548 117.858612)
				(xy 116.214548 117.85799) (xy 116.252752 117.616777) (xy 116.32822 117.384511) (xy 116.439093 117.166909)
				(xy 116.582642 116.969332) (xy 116.755332 116.796642) (xy 116.952909 116.653093) (xy 117.170511 116.54222)
				(xy 117.402777 116.466752) (xy 117.64399 116.428548) (xy 117.88821 116.428548)
			)
		)
	)
	(zone
		(layers "F.Cu" "B.Cu" "In1.Cu" "In2.Cu")
		(hatch edge 0.5)
		(connect_pads
			(clearance 0)
		)
		(min_thickness 0.25)
		(keepout
			(tracks not_allowed)
			(vias not_allowed)
			(pads not_allowed)
			(copperpour not_allowed)
			(footprints allowed)
		)
		(placement
			(enabled no)
			(sheetname "")
		)
		(fill
			(thermal_gap 0.5)
			(thermal_bridge_width 0.5)
			(island_removal_mode 0)
		)
		(polygon
			(pts
				(xy 182.083233 90.20367) (xy 182.086671 90.200233) (xy 182.091531 90.200233) (xy 182.094967 90.203671)
				(xy 182.09545 90.206101) (xy 182.09245 119.861101) (xy 182.091967 119.863531) (xy 182.088529 119.866967)
				(xy 182.083669 119.866967) (xy 182.080233 119.863529) (xy 182.07975 119.861099) (xy 182.08275 90.2061)
			)
		)
	)
	(zone
		(layers "F.Cu" "B.Cu" "In1.Cu" "In2.Cu")
		(hatch edge 0.5)
		(connect_pads
			(clearance 0)
		)
		(min_thickness 0.25)
		(keepout
			(tracks not_allowed)
			(vias not_allowed)
			(pads not_allowed)
			(copperpour not_allowed)
			(footprints allowed)
		)
		(placement
			(enabled no)
			(sheetname "")
		)
		(fill
			(thermal_gap 0.5)
			(thermal_bridge_width 0.5)
			(island_removal_mode 0)
		)
		(polygon
			(pts
				(xy 114.91945 90.2001) (xy 114.918237 90.203832) (xy 114.915062 90.206139) (xy 114.911138 90.206139)
				(xy 114.907963 90.203832) (xy 114.90675 90.2001) (xy 114.923098 90.01313) (xy 114.971646 89.831835)
				(xy 115.05092 89.661715) (xy 115.158515 89.507935) (xy 115.291165 89.375161) (xy 115.444844 89.267423)
				(xy 115.614889 89.18799) (xy 115.79614 89.139273) (xy 115.983094 89.12275) (xy 115.986828 89.123959)
				(xy 115.989137 89.127132) (xy 115.989141 89.131057) (xy 115.986837 89.134234) (xy 115.983106 89.13545)
				(xy 115.890016 89.135532) (xy 115.706692 89.168014) (xy 115.531788 89.231818) (xy 115.37061 89.325008)
				(xy 115.22805 89.444756) (xy 115.108436 89.587427) (xy 115.015396 89.748692) (xy 114.951756 89.923656)
				(xy 114.919445 90.10701) (xy 114.91945 90.2001)
			)
		)
	)
	(zone
		(layers "F.Cu" "B.Cu" "In1.Cu" "In2.Cu")
		(hatch edge 0.5)
		(connect_pads
			(clearance 0)
		)
		(min_thickness 0.25)
		(keepout
			(tracks not_allowed)
			(vias not_allowed)
			(pads not_allowed)
			(copperpour not_allowed)
			(footprints allowed)
		)
		(placement
			(enabled no)
			(sheetname "")
		)
		(fill
			(thermal_gap 0.5)
			(thermal_bridge_width 0.5)
			(island_removal_mode 0)
		)
		(polygon
			(pts
				(xy 118.129423 90.466752) (xy 118.361689 90.54222) (xy 118.579291 90.653093) (xy 118.776868 90.796642)
				(xy 118.949558 90.969332) (xy 119.093107 91.166909) (xy 119.20398 91.384511) (xy 119.279448 91.616777)
				(xy 119.317652 91.85799) (xy 119.317652 92.10221) (xy 119.279448 92.343423) (xy 119.20398 92.575689)
				(xy 119.093107 92.793291) (xy 118.949558 92.990868) (xy 118.776868 93.163558) (xy 118.579291 93.307107)
				(xy 118.361689 93.41798) (xy 118.129423 93.493448) (xy 117.88821 93.531652) (xy 117.64399 93.531652)
				(xy 117.402777 93.493448) (xy 117.170511 93.41798) (xy 116.952909 93.307107) (xy 116.755332 93.163558)
				(xy 116.582642 92.990868) (xy 116.439093 92.793291) (xy 116.32822 92.575689) (xy 116.252752 92.343423)
				(xy 116.214548 92.10221) (xy 116.214548 91.858612) (xy 116.22245 91.858612) (xy 116.22245 92.101588)
				(xy 116.26046 92.341572) (xy 116.335544 92.572656) (xy 116.445852 92.789149) (xy 116.58867 92.98572)
				(xy 116.76048 93.15753) (xy 116.957051 93.300348) (xy 117.173544 93.410656) (xy 117.404628 93.48574)
				(xy 117.644612 93.52375) (xy 117.887588 93.52375) (xy 118.127572 93.48574) (xy 118.358656 93.410656)
				(xy 118.575149 93.300348) (xy 118.77172 93.15753) (xy 118.94353 92.98572) (xy 119.086348 92.789149)
				(xy 119.196656 92.572656) (xy 119.27174 92.341572) (xy 119.30975 92.101588) (xy 119.30975 91.858612)
				(xy 119.27174 91.618628) (xy 119.196656 91.387544) (xy 119.086348 91.171051) (xy 118.94353 90.97448)
				(xy 118.77172 90.80267) (xy 118.575149 90.659852) (xy 118.358656 90.549544) (xy 118.127572 90.47446)
				(xy 117.887588 90.43645) (xy 117.644612 90.43645) (xy 117.404628 90.47446) (xy 117.173544 90.549544)
				(xy 116.957051 90.659852) (xy 116.76048 90.80267) (xy 116.58867 90.97448) (xy 116.445852 91.171051)
				(xy 116.335544 91.387544) (xy 116.26046 91.618628) (xy 116.22245 91.858612) (xy 116.214548 91.858612)
				(xy 116.214548 91.85799) (xy 116.252752 91.616777) (xy 116.32822 91.384511) (xy 116.439093 91.166909)
				(xy 116.582642 90.969332) (xy 116.755332 90.796642) (xy 116.952909 90.653093) (xy 117.170511 90.54222)
				(xy 117.402777 90.466752) (xy 117.64399 90.428548) (xy 117.88821 90.428548)
			)
		)
	)
	(zone
		(layer "F.Mask")
		(hatch edge 0.5)
		(priority 36)
		(connect_pads
			(clearance 0.5)
		)
		(min_thickness 0.25)
		(fill yes
			(thermal_gap 0.254)
			(thermal_bridge_width 0.254)
			(island_removal_mode 0)
		)
		(polygon
			(pts
				(arc
					(start 174.256095 94.193105)
					(mid 174.837402 95.47556)
					(end 176.144099 96.00011)
				)
				(xy 176.1441 96.0001) (xy 181.7861 96.0001)
				(arc
					(start 181.786105 90.123297)
					(mid 181.538537 89.629277)
					(end 181.023101 89.4301)
				)
				(xy 181.0231 89.4301) (xy 174.2561 89.4301) (xy 174.2561 94.1931)
			)
		)
	)
	(zone
		(layer "F.Mask")
		(hatch edge 0.5)
		(priority 34)
		(connect_pads
			(clearance 0.5)
		)
		(min_thickness 0.25)
		(fill yes
			(thermal_gap 0.254)
			(thermal_bridge_width 0.254)
			(island_removal_mode 0)
		)
		(polygon
			(pts
				(arc
					(start 115.216105 119.851403)
					(mid 115.452848 120.368764)
					(end 115.9811 120.58009)
				)
				(xy 115.9811 120.5801) (xy 121.7561 120.5801)
				(arc
					(start 121.756097 115.275097)
					(mid 121.337486 114.376306)
					(end 120.416099 114.0101)
				)
				(xy 120.4161 114.0101) (xy 115.2161 114.0101) (xy 115.2161 119.85141)
			)
		)
	)
	(zone
		(layer "F.Mask")
		(hatch edge 0.5)
		(priority 41)
		(connect_pads
			(clearance 0.5)
		)
		(min_thickness 0.25)
		(fill yes
			(thermal_gap 0.254)
			(thermal_bridge_width 0.254)
			(island_removal_mode 0)
		)
		(polygon
			(pts
				(xy 174.27685 120.59065)
				(arc
					(start 174.276848 115.695652)
					(mid 174.825209 114.506057)
					(end 176.04185 114.02065)
				)
				(xy 181.80685 114.02065)
				(arc
					(start 181.806851 119.882333)
					(mid 181.560599 120.386589)
					(end 181.037844 120.59065)
				)
				(xy 181.03785 120.59065)
			)
		)
	)
	(zone
		(layer "F.Mask")
		(hatch edge 0.5)
		(priority 40)
		(connect_pads
			(clearance 0.5)
		)
		(min_thickness 0.25)
		(fill yes
			(thermal_gap 0.254)
			(thermal_bridge_width 0.254)
			(island_removal_mode 0)
		)
		(polygon
			(pts
				(xy 115.2161 96.0001)
				(arc
					(start 115.2161 90.191242)
					(mid 115.439588 89.652981)
					(end 115.978101 89.4301)
				)
				(xy 115.9781 89.4301) (xy 121.7561 89.4301)
				(arc
					(start 121.756101 93.895101)
					(mid 120.994872 95.39602)
					(end 119.424103 96.0001)
				)
				(xy 119.4241 96.0001)
			)
		)
	)
	(zone
		(net "GND")
		(layer "B.Cu")
		(hatch edge 0.5)
		(priority 11)
		(connect_pads
			(clearance 0.5)
		)
		(min_thickness 0.25)
		(fill yes
			(thermal_gap 0.254)
			(thermal_bridge_width 0.254)
			(island_removal_mode 0)
		)
		(polygon
			(pts
				(xy 114.4071 88.7451) (xy 182.4791 88.7451) (xy 182.4791 121.2571) (xy 114.4071 121.2571)
			)
		)
	)
	(zone
		(layer "B.Mask")
		(hatch edge 0.5)
		(priority 21)
		(connect_pads
			(clearance 0.5)
		)
		(min_thickness 0.25)
		(fill yes
			(thermal_gap 0.254)
			(thermal_bridge_width 0.254)
			(island_removal_mode 0)
		)
		(polygon
			(pts
				(arc
					(start 115.216105 119.851403)
					(mid 115.452848 120.368764)
					(end 115.9811 120.58009)
				)
				(xy 115.9811 120.5801) (xy 121.7561 120.5801)
				(arc
					(start 121.756097 115.275097)
					(mid 121.337486 114.376306)
					(end 120.416099 114.0101)
				)
				(xy 120.4161 114.0101) (xy 115.2161 114.0101) (xy 115.2161 119.85141)
			)
		)
	)
	(zone
		(layer "B.Mask")
		(hatch edge 0.5)
		(priority 19)
		(connect_pads
			(clearance 0.5)
		)
		(min_thickness 0.25)
		(fill yes
			(thermal_gap 0.254)
			(thermal_bridge_width 0.254)
			(island_removal_mode 0)
		)
		(polygon
			(pts
				(xy 174.2561 120.5801)
				(arc
					(start 174.256098 115.685102)
					(mid 174.804459 114.495507)
					(end 176.0211 114.0101)
				)
				(xy 181.7861 114.0101)
				(arc
					(start 181.786111 119.871783)
					(mid 181.539859 120.376039)
					(end 181.017104 120.5801)
				)
				(xy 181.0171 120.5801)
			)
		)
	)
	(zone
		(layer "B.Mask")
		(hatch edge 0.5)
		(priority 30)
		(connect_pads
			(clearance 0.5)
		)
		(min_thickness 0.25)
		(fill yes
			(thermal_gap 0.254)
			(thermal_bridge_width 0.254)
			(island_removal_mode 0)
		)
		(polygon
			(pts
				(xy 115.2161 96.0001)
				(arc
					(start 115.2161 90.191242)
					(mid 115.439588 89.652981)
					(end 115.978101 89.4301)
				)
				(xy 115.9781 89.4301) (xy 121.7561 89.4301)
				(arc
					(start 121.756101 93.895101)
					(mid 120.994872 95.39602)
					(end 119.424103 96.0001)
				)
				(xy 119.4241 96.0001)
			)
		)
	)
	(zone
		(layer "B.Mask")
		(hatch edge 0.5)
		(priority 15)
		(connect_pads
			(clearance 0.5)
		)
		(min_thickness 0.25)
		(fill yes
			(thermal_gap 0.254)
			(thermal_bridge_width 0.254)
			(island_removal_mode 0)
		)
		(polygon
			(pts
				(arc
					(start 174.256095 94.193105)
					(mid 174.837402 95.47556)
					(end 176.144099 96.00011)
				)
				(xy 176.1441 96.0001) (xy 181.7861 96.0001)
				(arc
					(start 181.786105 90.123297)
					(mid 181.538537 89.629277)
					(end 181.023101 89.4301)
				)
				(xy 181.0231 89.4301) (xy 174.2561 89.4301) (xy 174.2561 94.1931)
			)
		)
	)
	(zone
		(net "GND")
		(layer "In1.Cu")
		(hatch edge 0.5)
		(priority 12)
		(connect_pads
			(clearance 0.5)
		)
		(min_thickness 0.25)
		(fill yes
			(thermal_gap 0.254)
			(thermal_bridge_width 0.254)
			(island_removal_mode 0)
		)
		(polygon
			(pts
				(xy 114.4071 88.7451) (xy 182.4791 88.7451) (xy 182.4791 121.2571) (xy 114.4071 121.2571)
			)
		)
	)
	(zone
		(net "GND")
		(layer "In2.Cu")
		(hatch edge 0.5)
		(connect_pads
			(clearance 0.5)
		)
		(min_thickness 0.25)
		(fill yes
			(thermal_gap 0.254)
			(thermal_bridge_width 0.254)
			(island_removal_mode 0)
		)
		(polygon
			(pts
				(xy 114.4071 88.7451) (xy 182.4791 88.7451) (xy 182.4791 121.2571) (xy 114.4071 121.2571)
			)
		)
	)
)
